FILE_TYPE = MACRO_DRAWING;
SET COLOR_WIRE YELLOW;
SET COLOR_PROP ORANGE;
SET COLOR_DOT WHITE;
SET COLOR_ARC YELLOW;
SET COLOR_BODY GREEN;
SET COLOR_NOTE PURPLE;
SET PROP_DISPLAY VALUE;
SET PAGE_NUMBER P343;
FORCEADD OFFPAGE..1
(-4350 5825);
PAINT AQUA (-4350 5825);
FORCEPROP 2 LAST $XR3 142 
J 0
(-4571 5753);
DISPLAY 0.638298 (-4571 5753);
PAINT MONO (-4571 5753);
FORCEPROP 2 LAST $XR2 141 
J 0
(-4571 5861);
DISPLAY 0.638298 (-4571 5861);
PAINT MONO (-4571 5861);
FORCEPROP 2 LAST $XR1 83 
J 0
(-4571 5789);
DISPLAY 0.638298 (-4571 5789);
PAINT MONO (-4571 5789);
FORCEPROP 2 LAST $XR0 81 
J 0
(-4571 5825);
DISPLAY 0.638298 (-4571 5825);
PAINT MONO (-4571 5825);
FORCEPROP 2 LAST CDS_LIB standard
J 0
(-4350 5825);
DISPLAY INVISIBLE (-4350 5825);
FORCEPROP 1 LAST OFFPAGE TRUE
J 0
(-4025 5700);
DISPLAY 0.872340 (-4025 5700);
PAINT AQUA (-4025 5700);
DISPLAY INVISIBLE (-4025 5700);
FORCEPROP 1 LAST COMMENT_BODY TRUE
J 0
(-4225 5725);
DISPLAY 0.872340 (-4225 5725);
PAINT GREEN (-4225 5725);
DISPLAY INVISIBLE (-4225 5725);
FORCEPROP 2 LAST PATH I1
J 0
(-4300 5900);
DISPLAY 0.680851 (-4300 5900);
DISPLAY INVISIBLE (-4300 5900);
FORCEADD MOSFET_NCH_DUAL..1
(-2800 5875);
FORCEPROP 1 LAST LOCATION Q118
J 0
(-2649 5849);
DISPLAY 0.723404 (-2649 5849);
PAINT GREEN (-2649 5849);
FORCEPROP 0 LAST $SEC 1
J 0
(-2625 6000);
DISPLAY 0.680851 (-2625 6000);
PAINT MONO (-2625 6000);
DISPLAY INVISIBLE (-2625 6000);
FORCEPROP 0 LAST CDS_SEC 1
J 0
(-2625 6000);
DISPLAY 1.021277 (-2625 6000);
DISPLAY INVISIBLE (-2625 6000);
FORCEPROP 0 LASTPIN (-2750 6075) $PN 6
R 1
J 0
(-2760 6085);
DISPLAY 0.680851 (-2760 6085);
PAINT MONO (-2760 6085);
FORCEPROP 0 LASTPIN (-3000 5825) $PN 2
J 2
(-3010 5835);
DISPLAY 0.680851 (-3010 5835);
PAINT MONO (-3010 5835);
FORCEPROP 0 LASTPIN (-2750 5675) $PN 1
R 1
J 2
(-2760 5665);
DISPLAY 0.680851 (-2760 5665);
PAINT MONO (-2760 5665);
FORCEPROP 0 LAST ROOM NIC_P12V_MAM_TIC_BOM1
J 0
(-2625 6050);
DISPLAY 0.680851 (-2625 6050);
PAINT RED (-2625 6050);
FORCEPROP 2 LAST VALUE PJT138K
J 0
(-2625 5900);
DISPLAY 1.021277 (-2625 5900);
FORCEPROP 2 LAST PART_TYPE SMLF
J 0
(-2625 5950);
DISPLAY 1.021277 (-2625 5950);
FORCEPROP 1 LAST MATERIAL IC
J 0
(-2649 5724);
DISPLAY 0.723404 (-2649 5724);
PAINT GREEN (-2649 5724);
FORCEPROP 1 LAST NEEDS_NO_SIZE TRUE
J 0
(-2800 5874);
DISPLAY 0.468085 (-2800 5874);
PAINT GREEN (-2800 5874);
DISPLAY INVISIBLE (-2800 5874);
FORCEPROP 1 LAST CDS_LMAN_SYM_OUTLINE -150,150,150,-150
J 0
(-2800 5875);
DISPLAY 0.468085 (-2800 5875);
PAINT GREEN (-2800 5875);
DISPLAY INVISIBLE (-2800 5875);
FORCEPROP 2 LAST CDS_LIB pure_quanta
J 0
(-2800 5875);
DISPLAY INVISIBLE (-2800 5875);
FORCEPROP 1 LAST PATH I10
J 0
(-2800 5875);
DISPLAY 0.723404 (-2800 5875);
PAINT GREEN (-2800 5875);
DISPLAY INVISIBLE (-2800 5875);
FORCEPROP 1 LAST PART_NUMBER BAM138K0003
J 0
(-2649 5789);
DISPLAY 0.723404 (-2649 5789);
PAINT GREEN (-2649 5789);
DISPLAY INVISIBLE (-2649 5789);
FORCEADD GND..1
(3975 6925);
FORCEPROP 3 LASTPIN (3975 6975) SIG_NAME GND\g
J 0
(3985 6985);
DISPLAY 0.659574 (3985 6985);
PAINT MONO (3985 6985);
DISPLAY INVISIBLE (3985 6985);
FORCEPROP 2 LAST CDS_LIB pure_quanta_power
J 0
(3975 6925);
DISPLAY INVISIBLE (3975 6925);
FORCEPROP 1 LAST SIZE 1B
J 0
(4050 6875);
DISPLAY 0.872340 (4050 6875);
PAINT GREEN (4050 6875);
DISPLAY INVISIBLE (4050 6875);
FORCEPROP 1 LAST HDL_POWER GND
J 0
(3975 7075);
DISPLAY 0.872340 (3975 7075);
PAINT GREEN (3975 7075);
DISPLAY INVISIBLE (3975 7075);
FORCEPROP 1 LAST PATH I100
J 0
(4050 6925);
DISPLAY 0.872340 (4050 6925);
PAINT AQUA (4050 6925);
DISPLAY INVISIBLE (4050 6925);
FORCEADD Q_CAP..1
(3975 7225);
FORCEPROP 1 LAST LOCATION PC2143
J 0
(4025 7325);
DISPLAY 0.680851 (4025 7325);
FORCEPROP 0 LAST $SEC 1
J 0
(4025 7375);
DISPLAY INVISIBLE (4025 7375);
FORCEPROP 0 LAST CDS_SEC 1
J 0
(4025 7375);
DISPLAY INVISIBLE (4025 7375);
FORCEPROP 1 LASTPIN (3975 7325) $PN 1
J 0
(3985 7305);
DISPLAY 0.787234 (3985 7305);
PAINT MONO (3985 7305);
DISPLAY INVISIBLE (3985 7305);
FORCEPROP 1 LASTPIN (3975 7125) $PN 2
J 0
(3985 7105);
DISPLAY 0.787234 (3985 7105);
PAINT MONO (3985 7105);
DISPLAY INVISIBLE (3985 7105);
FORCEPROP 1 LAST VALUE 10UF
J 0
(4025 7275);
DISPLAY 0.638298 (4025 7275);
FORCEPROP 1 LAST VOLTAGE 16V
J 0
(4025 7225);
DISPLAY 0.638298 (4025 7225);
FORCEPROP 1 LAST MATERIAL X6S
J 0
(4025 7175);
DISPLAY 0.638298 (4025 7175);
FORCEPROP 1 LAST PACK_TYPE C0805
J 0
(4025 7125);
DISPLAY 0.638298 (4025 7125);
FORCEPROP 1 LAST TOLERANCE 10%
J 0
(3764 7185);
DISPLAY 0.787234 (3764 7185);
PAINT GREEN (3764 7185);
DISPLAY INVISIBLE (3764 7185);
FORCEPROP 2 LAST CDS_LIB pure_quanta
J 0
(3975 7225);
DISPLAY INVISIBLE (3975 7225);
FORCEPROP 1 LAST PATH I101
J 0
(4025 7375);
DISPLAY 0.978723 (4025 7375);
PAINT WHITE (4025 7375);
DISPLAY INVISIBLE (4025 7375);
FORCEPROP 1 LAST PART_NUMBER CH6103KEA01
J 0
(4025 7075);
DISPLAY 0.638298 (4025 7075);
DISPLAY INVISIBLE (4025 7075);
FORCEADD UNIVERSAL_POWER..1
R 2
(3975 7525);
FORCEPROP 3 LASTPIN (3975 7475) SIG_NAME P12V_OCP_V3_2\g
J 0
(3985 7485);
DISPLAY 0.659574 (3985 7485);
PAINT MONO (3985 7485);
DISPLAY INVISIBLE (3985 7485);
FORCEPROP 1 LAST HDL_POWER P12V_OCP_V3_2
J 1
(4000 7575);
DISPLAY 0.723404 (4000 7575);
PAINT GREEN (4000 7575);
FORCEPROP 2 LAST CDS_LIB pure_quanta_power
J 0
(3975 7525);
DISPLAY INVISIBLE (3975 7525);
FORCEPROP 1 LAST PATH I102
J 2
(3925 7550);
DISPLAY 0.872340 (3925 7550);
PAINT AQUA (3925 7550);
DISPLAY INVISIBLE (3925 7550);
FORCEADD GND..1
(3175 8650);
FORCEPROP 3 LASTPIN (3175 8700) SIG_NAME GND\g
J 0
(3185 8710);
DISPLAY 0.659574 (3185 8710);
PAINT MONO (3185 8710);
DISPLAY INVISIBLE (3185 8710);
FORCEPROP 2 LAST CDS_LIB pure_quanta_power
J 0
(3175 8650);
DISPLAY INVISIBLE (3175 8650);
FORCEPROP 1 LAST SIZE 1B
J 0
(3250 8600);
DISPLAY 0.872340 (3250 8600);
PAINT GREEN (3250 8600);
DISPLAY INVISIBLE (3250 8600);
FORCEPROP 1 LAST HDL_POWER GND
J 0
(3175 8800);
DISPLAY 0.872340 (3175 8800);
PAINT GREEN (3175 8800);
DISPLAY INVISIBLE (3175 8800);
FORCEPROP 1 LAST PATH I103
J 0
(3250 8650);
DISPLAY 0.872340 (3250 8650);
PAINT AQUA (3250 8650);
DISPLAY INVISIBLE (3250 8650);
FORCEADD Q_CAP..1
(2400 8950);
FORCEPROP 1 LAST LOCATION PC2149
J 0
(2450 9050);
DISPLAY 0.510638 (2450 9050);
FORCEPROP 0 LAST $SEC 1
J 0
(2450 9100);
DISPLAY 0.680851 (2450 9100);
PAINT MONO (2450 9100);
DISPLAY INVISIBLE (2450 9100);
FORCEPROP 0 LAST CDS_SEC 1
J 0
(2450 9100);
DISPLAY 1.021277 (2450 9100);
DISPLAY INVISIBLE (2450 9100);
FORCEPROP 1 LASTPIN (2400 9050) $PN 1
J 0
(2410 9030);
DISPLAY 0.787234 (2410 9030);
PAINT MONO (2410 9030);
FORCEPROP 1 LASTPIN (2400 8850) $PN 2
J 0
(2410 8830);
DISPLAY 0.787234 (2410 8830);
PAINT MONO (2410 8830);
FORCEPROP 1 LAST VALUE 0.01UF
J 0
(2450 9025);
DISPLAY 0.404255 (2450 9025);
FORCEPROP 1 LAST VOLTAGE 50V
J 0
(2450 9000);
DISPLAY 0.404255 (2450 9000);
FORCEPROP 1 LAST MATERIAL EMPTY
J 0
(2450 8900);
DISPLAY 0.638298 (2450 8900);
PAINT RED (2450 8900);
FORCEPROP 0 LAST ROOM NIC_P3V3_BOM1
J 0
(2350 8800);
DISPLAY 0.446809 (2350 8800);
PAINT RED (2350 8800);
FORCEPROP 1 LAST PACK_TYPE C0402
J 0
(2450 8975);
DISPLAY 0.404255 (2450 8975);
FORCEPROP 1 LAST TOLERANCE 10%
J 0
(2450 8900);
DISPLAY 0.638298 (2450 8900);
DISPLAY INVISIBLE (2450 8900);
FORCEPROP 2 LAST CDS_LIB pure_quanta
J 0
(2400 8950);
DISPLAY INVISIBLE (2400 8950);
FORCEPROP 1 LAST PATH I104
J 0
(2450 9100);
DISPLAY 0.978723 (2450 9100);
PAINT WHITE (2450 9100);
DISPLAY INVISIBLE (2450 9100);
FORCEPROP 1 LAST PART_NUMBER CH31006KB18
J 0
(2450 8950);
DISPLAY 0.404255 (2450 8950);
DISPLAY INVISIBLE (2450 8950);
FORCEADD Q_RES..2
(2675 8975);
FORCEPROP 1 LAST LOCATION PR4523
J 0
(2720 9100);
DISPLAY 0.978723 (2720 9100);
FORCEPROP 0 LAST $SEC 1
J 0
(2725 9150);
DISPLAY 0.680851 (2725 9150);
PAINT MONO (2725 9150);
DISPLAY INVISIBLE (2725 9150);
FORCEPROP 0 LAST CDS_SEC 1
J 0
(2725 9150);
DISPLAY 1.021277 (2725 9150);
DISPLAY INVISIBLE (2725 9150);
FORCEPROP 1 LASTPIN (2675 9075) $PN 1
J 0
(2680 9037);
DISPLAY 0.787234 (2680 9037);
PAINT MONO (2680 9037);
FORCEPROP 1 LASTPIN (2675 8875) $PN 2
J 0
(2680 8885);
DISPLAY 0.787234 (2680 8885);
PAINT MONO (2680 8885);
FORCEPROP 1 LAST WATTAGE 1/16W
J 0
(2725 9025);
DISPLAY 0.510638 (2725 9025);
FORCEPROP 1 LAST VALUE 10M
J 0
(2725 9075);
DISPLAY 0.510638 (2725 9075);
FORCEPROP 1 LAST PACK_TYPE 0402LF
J 0
(2725 8950);
DISPLAY 0.510638 (2725 8950);
FORCEPROP 1 LAST MATERIAL CHIP
J 0
(2725 9000);
DISPLAY 0.510638 (2725 9000);
FORCEPROP 0 LAST ROOM NIC_P3V3_BOM1
J 0
(2725 9175);
DISPLAY 0.680851 (2725 9175);
PAINT RED (2725 9175);
FORCEPROP 1 LAST TOLERANCE 1%
J 0
(2725 9050);
DISPLAY 0.510638 (2725 9050);
FORCEPROP 2 LAST CDS_LIB pure_quanta
J 0
(2675 8975);
DISPLAY INVISIBLE (2675 8975);
FORCEPROP 1 LAST PATH I105
J 0
(2725 9150);
DISPLAY 0.978723 (2725 9150);
PAINT WHITE (2725 9150);
DISPLAY INVISIBLE (2725 9150);
FORCEPROP 1 LAST PART_NUMBER CS61002FB02
J 0
(2725 8975);
DISPLAY 0.510638 (2725 8975);
DISPLAY INVISIBLE (2725 8975);
FORCEADD SCHOTTKY_AC..1
R 1
(2800 9575);
FORCEPROP 1 LAST LOCATION PD109
J 0
(2850 9600);
DISPLAY 0.723404 (2850 9600);
PAINT GREEN (2850 9600);
FORCEPROP 0 LAST $SEC 1
R 1
J 0
(2850 9650);
DISPLAY INVISIBLE (2850 9650);
FORCEPROP 0 LAST CDS_SEC 1
R 1
J 0
(2850 9650);
DISPLAY INVISIBLE (2850 9650);
FORCEPROP 0 LASTPIN (2800 9450) $PN A
R 1
J 2
(2790 9485);
DISPLAY 0.808511 (2790 9485);
FORCEPROP 0 LASTPIN (2800 9700) $PN C
R 1
J 0
(2790 9660);
DISPLAY 0.808511 (2790 9660);
FORCEPROP 2 LAST VALUE B340A-13-F
J 0
(2850 9550);
DISPLAY 0.638298 (2850 9550);
FORCEPROP 1 LAST CDS_LMAN_SYM_OUTLINE -75,50,75,-50
R 1
J 0
(2800 9575);
DISPLAY 0.468085 (2800 9575);
PAINT GREEN (2800 9575);
DISPLAY INVISIBLE (2800 9575);
FORCEPROP 2 LAST CDS_LIB pure_quanta
R 1
J 0
(2800 9575);
DISPLAY INVISIBLE (2800 9575);
FORCEPROP 1 LAST NEEDS_NO_SIZE TRUE
R 1
J 0
(2850 9650);
DISPLAY 0.468085 (2850 9650);
PAINT GREEN (2850 9650);
DISPLAY INVISIBLE (2850 9650);
FORCEPROP 0 LAST PART_TYPE SMLF
J 0
(2850 9750);
DISPLAY 1.021277 (2850 9750);
DISPLAY INVISIBLE (2850 9750);
FORCEPROP 1 LAST MATERIAL IC
J 0
(2850 9475);
DISPLAY 0.723404 (2850 9475);
PAINT GREEN (2850 9475);
DISPLAY INVISIBLE (2850 9475);
FORCEPROP 1 LAST PATH I106
R 1
J 0
(2800 9575);
DISPLAY 0.723404 (2800 9575);
PAINT GREEN (2800 9575);
DISPLAY INVISIBLE (2800 9575);
FORCEPROP 1 LAST PART_NUMBER BC000340Z30
J 0
(2850 9500);
DISPLAY 0.595745 (2850 9500);
PAINT GREEN (2850 9500);
DISPLAY INVISIBLE (2850 9500);
FORCEADD Q_RES..2
(3425 8925);
FORCEPROP 1 LAST LOCATION R3833
J 0
(3475 8950);
DISPLAY 0.638298 (3475 8950);
FORCEPROP 0 LAST $SEC 1
J 0
(3475 9100);
DISPLAY 0.680851 (3475 9100);
PAINT MONO (3475 9100);
DISPLAY INVISIBLE (3475 9100);
FORCEPROP 0 LAST CDS_SEC 1
J 0
(3475 9100);
DISPLAY 1.021277 (3475 9100);
DISPLAY INVISIBLE (3475 9100);
FORCEPROP 1 LASTPIN (3425 9025) $PN 1
J 0
(3430 8987);
DISPLAY 0.787234 (3430 8987);
PAINT MONO (3430 8987);
FORCEPROP 1 LASTPIN (3425 8825) $PN 2
J 0
(3430 8835);
DISPLAY 0.787234 (3430 8835);
PAINT MONO (3430 8835);
FORCEPROP 1 LAST TOLERANCE 1%
J 0
(3475 8900);
DISPLAY 0.510638 (3475 8900);
FORCEPROP 1 LAST PACK_TYPE 0402LF
J 0
(3475 8800);
DISPLAY 0.510638 (3475 8800);
FORCEPROP 1 LAST MATERIAL CHIP
J 0
(3475 8850);
DISPLAY 0.510638 (3475 8850);
FORCEPROP 1 LAST WATTAGE 1/16W
J 0
(3475 8875);
DISPLAY 0.510638 (3475 8875);
FORCEPROP 1 LAST VALUE 100K
J 0
(3475 8925);
DISPLAY 0.510638 (3475 8925);
FORCEPROP 0 LAST ROOM NIC_P3V3_BOM1
J 0
(3475 9000);
DISPLAY 0.680851 (3475 9000);
PAINT RED (3475 9000);
FORCEPROP 2 LAST CDS_LIB pure_quanta
J 0
(3425 8925);
DISPLAY INVISIBLE (3425 8925);
FORCEPROP 1 LAST PATH I107
J 0
(3475 9100);
DISPLAY 0.978723 (3475 9100);
PAINT WHITE (3475 9100);
DISPLAY INVISIBLE (3475 9100);
FORCEPROP 1 LAST PART_NUMBER CS41002FB09
J 0
(3475 8825);
DISPLAY 0.510638 (3475 8825);
DISPLAY INVISIBLE (3475 8825);
FORCEADD Q_CAP..1
(3300 9550);
FORCEPROP 1 LAST LOCATION PC2137
J 0
(3350 9650);
DISPLAY 0.638298 (3350 9650);
FORCEPROP 0 LAST $SEC 1
J 0
(3350 9700);
DISPLAY 0.680851 (3350 9700);
PAINT MONO (3350 9700);
DISPLAY INVISIBLE (3350 9700);
FORCEPROP 0 LAST CDS_SEC 1
J 0
(3350 9700);
DISPLAY 1.021277 (3350 9700);
DISPLAY INVISIBLE (3350 9700);
FORCEPROP 1 LASTPIN (3300 9650) $PN 1
J 0
(3310 9630);
DISPLAY 0.787234 (3310 9630);
PAINT MONO (3310 9630);
FORCEPROP 1 LASTPIN (3300 9450) $PN 2
J 0
(3310 9430);
DISPLAY 0.787234 (3310 9430);
PAINT MONO (3310 9430);
FORCEPROP 1 LAST VALUE 0.1UF
J 0
(3350 9600);
DISPLAY 0.638298 (3350 9600);
FORCEPROP 1 LAST MATERIAL X7R
J 0
(3350 9500);
DISPLAY 0.638298 (3350 9500);
FORCEPROP 1 LAST VOLTAGE 25V
J 0
(3350 9550);
DISPLAY 0.638298 (3350 9550);
FORCEPROP 1 LAST PACK_TYPE 0402
J 0
(3350 9450);
DISPLAY 0.638298 (3350 9450);
FORCEPROP 1 LAST TOLERANCE 10%
J 0
(3350 9500);
DISPLAY 0.978723 (3350 9500);
DISPLAY INVISIBLE (3350 9500);
FORCEPROP 2 LAST CDS_LIB pure_quanta
J 0
(3300 9550);
DISPLAY INVISIBLE (3300 9550);
FORCEPROP 1 LAST PATH I108
J 0
(3350 9700);
DISPLAY 0.978723 (3350 9700);
PAINT WHITE (3350 9700);
DISPLAY INVISIBLE (3350 9700);
FORCEPROP 1 LAST PART_NUMBER CH4104K1B00
J 0
(3350 9400);
DISPLAY 0.638298 (3350 9400);
DISPLAY INVISIBLE (3350 9400);
FORCEADD OFFPAGE..1
(-2700 5025);
FORCEPROP 2 LAST $XR1 143 
J 0
(-3072 5025);
DISPLAY 0.638298 (-3072 5025);
PAINT MONO (-3072 5025);
FORCEPROP 2 LAST $XR0 137 
J 0
(-2952 5025);
DISPLAY 0.638298 (-2952 5025);
PAINT MONO (-2952 5025);
FORCEPROP 2 LAST CDS_LIB standard
J 0
(-2700 5025);
PAINT MONO (-2700 5025);
DISPLAY INVISIBLE (-2700 5025);
FORCEPROP 1 LAST OFFPAGE TRUE
J 0
(-2375 4900);
DISPLAY 0.872340 (-2375 4900);
PAINT GREEN (-2375 4900);
DISPLAY INVISIBLE (-2375 4900);
FORCEPROP 1 LAST COMMENT_BODY TRUE
J 0
(-2575 4925);
DISPLAY 0.872340 (-2575 4925);
PAINT GREEN (-2575 4925);
DISPLAY INVISIBLE (-2575 4925);
FORCEPROP 2 LAST PATH I11
J 0
(-2975 5075);
DISPLAY 0.680851 (-2975 5075);
DISPLAY INVISIBLE (-2975 5075);
FORCEADD VCCAUX15..1
(3625 9250);
FORCEPROP 3 LASTPIN (3625 9200) SIG_NAME P3V3_AUX\g
J 0
(3635 9210);
DISPLAY 0.659574 (3635 9210);
PAINT MONO (3635 9210);
DISPLAY INVISIBLE (3635 9210);
FORCEPROP 1 LAST HDL_POWER P3V3_AUX
J 1
(3625 9300);
DISPLAY 0.723404 (3625 9300);
PAINT GREEN (3625 9300);
FORCEPROP 2 LAST CDS_LIB pure_quanta_power
J 0
(3625 9250);
DISPLAY INVISIBLE (3625 9250);
FORCEPROP 1 LAST PATH I110
J 0
(3675 9275);
DISPLAY 0.872340 (3675 9275);
PAINT AQUA (3675 9275);
DISPLAY INVISIBLE (3675 9275);
FORCEADD GND..1
(3875 9250);
FORCEPROP 3 LASTPIN (3875 9300) SIG_NAME GND\g
J 0
(3885 9310);
DISPLAY 0.659574 (3885 9310);
PAINT MONO (3885 9310);
DISPLAY INVISIBLE (3885 9310);
FORCEPROP 1 LAST SIZE 1B
J 0
(3950 9200);
DISPLAY 0.872340 (3950 9200);
PAINT GREEN (3950 9200);
DISPLAY INVISIBLE (3950 9200);
FORCEPROP 2 LAST CDS_LIB pure_quanta_power
J 0
(3875 9250);
DISPLAY INVISIBLE (3875 9250);
FORCEPROP 1 LAST HDL_POWER GND
J 0
(3875 9400);
DISPLAY 0.872340 (3875 9400);
PAINT GREEN (3875 9400);
DISPLAY INVISIBLE (3875 9400);
FORCEPROP 1 LAST PATH I111
J 0
(3950 9250);
DISPLAY 0.872340 (3950 9250);
PAINT AQUA (3950 9250);
DISPLAY INVISIBLE (3950 9250);
FORCEADD Q_CAP..1
(3875 9550);
FORCEPROP 1 LAST LOCATION PC2142
J 0
(3925 9650);
DISPLAY 0.680851 (3925 9650);
FORCEPROP 0 LAST $SEC 1
J 0
(3925 9700);
DISPLAY INVISIBLE (3925 9700);
FORCEPROP 0 LAST CDS_SEC 1
J 0
(3925 9700);
DISPLAY INVISIBLE (3925 9700);
FORCEPROP 1 LASTPIN (3875 9650) $PN 1
J 0
(3885 9630);
DISPLAY 0.787234 (3885 9630);
PAINT MONO (3885 9630);
DISPLAY INVISIBLE (3885 9630);
FORCEPROP 1 LASTPIN (3875 9450) $PN 2
J 0
(3885 9430);
DISPLAY 0.787234 (3885 9430);
PAINT MONO (3885 9430);
DISPLAY INVISIBLE (3885 9430);
FORCEPROP 1 LAST MATERIAL X6S
J 0
(3925 9500);
DISPLAY 0.638298 (3925 9500);
FORCEPROP 1 LAST VOLTAGE 16V
J 0
(3925 9550);
DISPLAY 0.638298 (3925 9550);
FORCEPROP 1 LAST VALUE 10UF
J 0
(3925 9600);
DISPLAY 0.638298 (3925 9600);
FORCEPROP 1 LAST PACK_TYPE C0805
J 0
(3925 9450);
DISPLAY 0.638298 (3925 9450);
FORCEPROP 2 LAST CDS_LIB pure_quanta
J 0
(3875 9550);
DISPLAY INVISIBLE (3875 9550);
FORCEPROP 1 LAST TOLERANCE 10%
J 0
(3664 9510);
DISPLAY 0.787234 (3664 9510);
PAINT GREEN (3664 9510);
DISPLAY INVISIBLE (3664 9510);
FORCEPROP 1 LAST PATH I112
J 0
(3925 9700);
DISPLAY 0.978723 (3925 9700);
PAINT WHITE (3925 9700);
DISPLAY INVISIBLE (3925 9700);
FORCEPROP 1 LAST PART_NUMBER CH6103KEA01
J 0
(3925 9400);
DISPLAY 0.638298 (3925 9400);
DISPLAY INVISIBLE (3925 9400);
FORCEADD UNIVERSAL_POWER..1
R 2
(3875 9850);
FORCEPROP 3 LASTPIN (3875 9800) SIG_NAME P3V3_OCP_V3_2_R\g
J 0
(3885 9810);
DISPLAY 0.659574 (3885 9810);
PAINT MONO (3885 9810);
DISPLAY INVISIBLE (3885 9810);
FORCEPROP 1 LAST HDL_POWER P3V3_OCP_V3_2_R
J 1
(3875 9900);
DISPLAY 0.723404 (3875 9900);
PAINT GREEN (3875 9900);
FORCEPROP 2 LAST CDS_LIB pure_quanta_power
J 0
(3875 9850);
DISPLAY INVISIBLE (3875 9850);
FORCEPROP 1 LAST PATH I113
J 2
(3825 9875);
DISPLAY 0.872340 (3825 9875);
PAINT AQUA (3825 9875);
DISPLAY INVISIBLE (3825 9875);
FORCEADD OFFPAGE..2
(4225 8625);
PAINT AQUA (4225 8625);
FORCEPROP 2 LAST $XR0 142 
J 0
(4414 8625);
DISPLAY 0.638298 (4414 8625);
PAINT MONO (4414 8625);
FORCEPROP 2 LAST CDS_LIB standard
J 0
(4225 8625);
DISPLAY INVISIBLE (4225 8625);
FORCEPROP 1 LAST OFFPAGE TRUE
J 0
(4550 8500);
DISPLAY 0.872340 (4550 8500);
PAINT AQUA (4550 8500);
DISPLAY INVISIBLE (4550 8500);
FORCEPROP 1 LAST COMMENT_BODY TRUE
J 0
(4180 8530);
DISPLAY 0.872340 (4180 8530);
PAINT GREEN (4180 8530);
DISPLAY INVISIBLE (4180 8530);
FORCEPROP 2 LAST PATH I114
J 0
(4425 8675);
DISPLAY 0.680851 (4425 8675);
DISPLAY INVISIBLE (4425 8675);
FORCEADD UNIVERSAL_POWER..1
(1925 5225);
FORCEPROP 3 LASTPIN (1925 5175) SIG_NAME P3V3_AUX\g
J 0
(1935 5185);
DISPLAY 0.659574 (1935 5185);
PAINT MONO (1935 5185);
DISPLAY INVISIBLE (1935 5185);
FORCEPROP 1 LAST HDL_POWER P3V3_AUX
J 1
(1925 5275);
DISPLAY 0.872340 (1925 5275);
PAINT GREEN (1925 5275);
FORCEPROP 2 LAST CDS_LIB pure_quanta_power
J 0
(1925 5225);
PAINT MONO (1925 5225);
DISPLAY INVISIBLE (1925 5225);
FORCEPROP 1 LAST PATH I115
J 0
(1975 5250);
DISPLAY 0.872340 (1975 5250);
PAINT AQUA (1975 5250);
DISPLAY INVISIBLE (1975 5250);
FORCEADD Q_RES..1
(425 4275);
FORCEPROP 1 LAST LOCATION R1191
J 0
(225 4275);
DISPLAY 0.638298 (225 4275);
FORCEPROP 0 LAST $SEC 1
J 0
(225 4325);
DISPLAY 0.680851 (225 4325);
PAINT MONO (225 4325);
DISPLAY INVISIBLE (225 4325);
FORCEPROP 0 LAST CDS_SEC 1
J 0
(225 4325);
DISPLAY 0.680851 (225 4325);
DISPLAY INVISIBLE (225 4325);
FORCEPROP 1 LASTPIN (325 4275) $PN 1
J 0
(337 4287);
DISPLAY 0.787234 (337 4287);
PAINT MONO (337 4287);
FORCEPROP 1 LASTPIN (525 4275) $PN 2
J 0
(487 4287);
DISPLAY 0.787234 (487 4287);
PAINT MONO (487 4287);
FORCEPROP 1 LAST WATTAGE 1/16W
J 2
(550 4200);
DISPLAY 0.404255 (550 4200);
FORCEPROP 1 LAST PACK_TYPE 0402LF
J 0
(650 4275);
DISPLAY 0.404255 (650 4275);
FORCEPROP 1 LAST TOLERANCE 5%
J 0
(600 4275);
DISPLAY 0.404255 (600 4275);
FORCEPROP 1 LAST MATERIAL CHIP
J 0
(350 4200);
DISPLAY 0.404255 (350 4200);
FORCEPROP 1 LAST VALUE 0
J 2
(575 4275);
DISPLAY 0.404255 (575 4275);
FORCEPROP 2 LAST CDS_LIB pure_quanta
J 0
(425 4275);
DISPLAY INVISIBLE (425 4275);
FORCEPROP 1 LAST PATH I116
J 0
(375 4425);
DISPLAY 0.978723 (375 4425);
PAINT WHITE (375 4425);
DISPLAY INVISIBLE (375 4425);
FORCEPROP 1 LAST PART_NUMBER CS00002JB13
J 0
(350 4225);
DISPLAY 0.404255 (350 4225);
DISPLAY INVISIBLE (350 4225);
FORCEADD OFFPAGE..2
(2075 4275);
FORCEPROP 2 LAST $XR0 142 
J 0
(2264 4275);
DISPLAY 0.638298 (2264 4275);
PAINT MONO (2264 4275);
FORCEPROP 2 LAST CDS_LIB standard
J 0
(2075 4275);
DISPLAY INVISIBLE (2075 4275);
FORCEPROP 1 LAST OFFPAGE TRUE
J 0
(2400 4150);
DISPLAY 0.872340 (2400 4150);
DISPLAY INVISIBLE (2400 4150);
FORCEPROP 1 LAST COMMENT_BODY TRUE
J 0
(2030 4180);
DISPLAY 0.872340 (2030 4180);
PAINT GREEN (2030 4180);
DISPLAY INVISIBLE (2030 4180);
FORCEPROP 2 LAST PATH I117
J 0
(2250 4350);
DISPLAY 0.680851 (2250 4350);
DISPLAY INVISIBLE (2250 4350);
FORCEADD Q_RES..2
R 2
(1750 4950);
FORCEPROP 1 LAST LOCATION R1192
J 2
(1705 5075);
DISPLAY 0.978723 (1705 5075);
FORCEPROP 0 LAST $SEC 1
J 0
(1725 5125);
DISPLAY 0.680851 (1725 5125);
PAINT MONO (1725 5125);
DISPLAY INVISIBLE (1725 5125);
FORCEPROP 0 LAST CDS_SEC 1
J 0
(1725 5125);
DISPLAY 0.680851 (1725 5125);
DISPLAY INVISIBLE (1725 5125);
FORCEPROP 1 LASTPIN (1750 5050) $PN 1
J 2
(1745 5012);
DISPLAY 0.787234 (1745 5012);
PAINT MONO (1745 5012);
FORCEPROP 1 LASTPIN (1750 4850) $PN 2
J 2
(1745 4860);
DISPLAY 0.787234 (1745 4860);
PAINT MONO (1745 4860);
FORCEPROP 1 LAST MATERIAL CHIP
J 2
(1710 4875);
DISPLAY 0.510638 (1710 4875);
FORCEPROP 1 LAST WATTAGE 1/16W
J 2
(1710 4925);
DISPLAY 0.510638 (1710 4925);
FORCEPROP 1 LAST TOLERANCE 1%
J 2
(1705 4975);
DISPLAY 0.510638 (1705 4975);
FORCEPROP 1 LAST PACK_TYPE 0402LF
J 2
(1710 4825);
DISPLAY 0.510638 (1710 4825);
FORCEPROP 1 LAST VALUE 1K
J 2
(1705 5025);
DISPLAY 0.510638 (1705 5025);
FORCEPROP 2 LAST CDS_LIB pure_quanta
J 2
(1750 4950);
DISPLAY INVISIBLE (1750 4950);
FORCEPROP 1 LAST PATH I118
J 2
(1700 5125);
DISPLAY 0.978723 (1700 5125);
PAINT WHITE (1700 5125);
DISPLAY INVISIBLE (1700 5125);
FORCEPROP 1 LAST PART_NUMBER CS21002FB06
J 2
(1710 4775);
DISPLAY 0.510638 (1710 4775);
DISPLAY INVISIBLE (1710 4775);
FORCEADD Q_RES..1
(-3775 5825);
FORCEPROP 1 LAST LOCATION R4059
J 0
(-3825 5850);
DISPLAY 0.638298 (-3825 5850);
FORCEPROP 0 LAST $SEC 1
J 0
(-3825 5900);
DISPLAY 0.680851 (-3825 5900);
PAINT MONO (-3825 5900);
DISPLAY INVISIBLE (-3825 5900);
FORCEPROP 0 LAST CDS_SEC 1
J 0
(-3825 5900);
DISPLAY 0.680851 (-3825 5900);
DISPLAY INVISIBLE (-3825 5900);
FORCEPROP 1 LASTPIN (-3875 5825) $PN 1
J 0
(-3863 5837);
DISPLAY 0.787234 (-3863 5837);
PAINT MONO (-3863 5837);
FORCEPROP 1 LASTPIN (-3675 5825) $PN 2
J 0
(-3713 5837);
DISPLAY 0.787234 (-3713 5837);
PAINT MONO (-3713 5837);
FORCEPROP 1 LAST TOLERANCE 5%
J 0
(-3600 5825);
DISPLAY 0.510638 (-3600 5825);
FORCEPROP 1 LAST VALUE 0
J 2
(-3625 5825);
DISPLAY 0.510638 (-3625 5825);
FORCEPROP 1 LAST MATERIAL EMPTY
J 0
(-3825 5775);
DISPLAY 0.510638 (-3825 5775);
PAINT RED (-3825 5775);
FORCEPROP 0 LAST ROOM NIC_P12V_MAM_TIC_BOM1
J 0
(-4075 5725);
DISPLAY 0.553191 (-4075 5725);
PAINT RED (-4075 5725);
FORCEPROP 2 LAST CDS_LIB pure_quanta
J 0
(-3775 5825);
DISPLAY INVISIBLE (-3775 5825);
FORCEPROP 1 LAST PACK_TYPE 0402LF
J 0
(-3525 5825);
DISPLAY 0.510638 (-3525 5825);
DISPLAY INVISIBLE (-3525 5825);
FORCEPROP 1 LAST WATTAGE 1/16W
J 2
(-3675 5750);
DISPLAY 0.319149 (-3675 5750);
DISPLAY INVISIBLE (-3675 5750);
FORCEPROP 1 LAST PATH I119
J 0
(-3825 5975);
DISPLAY 0.978723 (-3825 5975);
PAINT WHITE (-3825 5975);
DISPLAY INVISIBLE (-3825 5975);
FORCEPROP 1 LAST PART_NUMBER CS00002JB13
J 0
(-3850 5775);
DISPLAY 0.319149 (-3850 5775);
DISPLAY INVISIBLE (-3850 5775);
FORCEADD OFFPAGE..1
(-2700 5125);
FORCEPROP 2 LAST $XR1 143 
J 0
(-3072 5125);
DISPLAY 0.638298 (-3072 5125);
PAINT MONO (-3072 5125);
FORCEPROP 2 LAST $XR0 137 
J 0
(-2952 5125);
DISPLAY 0.638298 (-2952 5125);
PAINT MONO (-2952 5125);
FORCEPROP 2 LAST CDS_LIB standard
J 0
(-2700 5125);
PAINT MONO (-2700 5125);
DISPLAY INVISIBLE (-2700 5125);
FORCEPROP 1 LAST OFFPAGE TRUE
J 0
(-2375 5000);
DISPLAY 0.872340 (-2375 5000);
PAINT GREEN (-2375 5000);
DISPLAY INVISIBLE (-2375 5000);
FORCEPROP 1 LAST COMMENT_BODY TRUE
J 0
(-2575 5025);
DISPLAY 0.872340 (-2575 5025);
PAINT GREEN (-2575 5025);
DISPLAY INVISIBLE (-2575 5025);
FORCEPROP 2 LAST PATH I12
J 0
(-2975 5175);
DISPLAY 0.680851 (-2975 5175);
DISPLAY INVISIBLE (-2975 5175);
FORCEADD Q_RES..2
R 2
(-3075 5550);
FORCEPROP 1 LAST LOCATION R6060
J 2
(-3120 5675);
DISPLAY 0.808511 (-3120 5675);
FORCEPROP 0 LAST $SEC 1
J 0
(-3100 5725);
DISPLAY 0.680851 (-3100 5725);
PAINT MONO (-3100 5725);
DISPLAY INVISIBLE (-3100 5725);
FORCEPROP 0 LAST CDS_SEC 1
J 0
(-3100 5725);
DISPLAY 0.680851 (-3100 5725);
DISPLAY INVISIBLE (-3100 5725);
FORCEPROP 1 LASTPIN (-3075 5650) $PN 1
J 2
(-3080 5612);
DISPLAY 0.787234 (-3080 5612);
PAINT MONO (-3080 5612);
FORCEPROP 1 LASTPIN (-3075 5450) $PN 2
J 2
(-3080 5460);
DISPLAY 0.787234 (-3080 5460);
PAINT MONO (-3080 5460);
FORCEPROP 0 LAST ROOM NIC_P12V_MAM_TIC_BOM1
J 0
(-3675 5325);
DISPLAY 0.553191 (-3675 5325);
PAINT RED (-3675 5325);
FORCEPROP 1 LAST PACK_TYPE 0402LF
J 2
(-3115 5375);
DISPLAY 0.638298 (-3115 5375);
FORCEPROP 1 LAST WATTAGE 1/16W
J 2
(-3115 5525);
DISPLAY 0.638298 (-3115 5525);
FORCEPROP 1 LAST TOLERANCE 5%
J 2
(-3120 5575);
DISPLAY 0.638298 (-3120 5575);
FORCEPROP 1 LAST VALUE 4.7K
J 2
(-3120 5625);
DISPLAY 0.638298 (-3120 5625);
FORCEPROP 1 LAST MATERIAL EMPTY
J 2
(-3115 5475);
DISPLAY 0.638298 (-3115 5475);
PAINT RED (-3115 5475);
FORCEPROP 2 LAST CDS_LIB pure_quanta
J 0
(-3075 5550);
DISPLAY INVISIBLE (-3075 5550);
FORCEPROP 1 LAST PATH I120
J 2
(-3125 5725);
DISPLAY 0.978723 (-3125 5725);
PAINT WHITE (-3125 5725);
DISPLAY INVISIBLE (-3125 5725);
FORCEPROP 1 LAST PART_NUMBER CS24702JB10
J 2
(-3115 5425);
DISPLAY 0.638298 (-3115 5425);
DISPLAY INVISIBLE (-3115 5425);
FORCEADD Q_RES..2
R 2
(-2725 7500);
FORCEPROP 1 LAST LOCATION R4066
J 2
(-2770 7625);
DISPLAY 0.808511 (-2770 7625);
FORCEPROP 0 LAST $SEC 1
J 0
(-2750 7675);
DISPLAY 0.680851 (-2750 7675);
PAINT MONO (-2750 7675);
DISPLAY INVISIBLE (-2750 7675);
FORCEPROP 0 LAST CDS_SEC 1
J 0
(-2750 7675);
DISPLAY 0.680851 (-2750 7675);
DISPLAY INVISIBLE (-2750 7675);
FORCEPROP 1 LASTPIN (-2725 7600) $PN 1
J 2
(-2730 7562);
DISPLAY 0.787234 (-2730 7562);
PAINT MONO (-2730 7562);
FORCEPROP 1 LASTPIN (-2725 7400) $PN 2
J 2
(-2730 7410);
DISPLAY 0.787234 (-2730 7410);
PAINT MONO (-2730 7410);
FORCEPROP 0 LAST ROOM NIC_P3V3_BOM1
J 0
(-3175 7250);
DISPLAY 0.680851 (-3175 7250);
PAINT RED (-3175 7250);
FORCEPROP 1 LAST PACK_TYPE 0402LF
J 2
(-2765 7325);
DISPLAY 0.638298 (-2765 7325);
FORCEPROP 1 LAST WATTAGE 1/16W
J 2
(-2765 7475);
DISPLAY 0.638298 (-2765 7475);
FORCEPROP 1 LAST TOLERANCE 5%
J 2
(-2770 7525);
DISPLAY 0.638298 (-2770 7525);
FORCEPROP 1 LAST VALUE 4.7K
J 2
(-2770 7575);
DISPLAY 0.638298 (-2770 7575);
FORCEPROP 1 LAST MATERIAL EMPTY
J 2
(-2765 7425);
DISPLAY 0.638298 (-2765 7425);
PAINT RED (-2765 7425);
FORCEPROP 2 LAST CDS_LIB pure_quanta
J 0
(-2725 7500);
DISPLAY INVISIBLE (-2725 7500);
FORCEPROP 1 LAST PATH I121
J 2
(-2775 7675);
DISPLAY 0.978723 (-2775 7675);
PAINT WHITE (-2775 7675);
DISPLAY INVISIBLE (-2775 7675);
FORCEPROP 1 LAST PART_NUMBER CS24702JB10
J 2
(-2765 7375);
DISPLAY 0.638298 (-2765 7375);
DISPLAY INVISIBLE (-2765 7375);
FORCEADD Q_RES..1
(-3175 7825);
FORCEPROP 1 LAST LOCATION R4060
J 0
(-3225 7850);
DISPLAY 0.638298 (-3225 7850);
FORCEPROP 0 LAST $SEC 1
J 0
(-3225 7900);
DISPLAY 0.680851 (-3225 7900);
PAINT MONO (-3225 7900);
DISPLAY INVISIBLE (-3225 7900);
FORCEPROP 0 LAST CDS_SEC 1
J 0
(-3225 7900);
DISPLAY 0.680851 (-3225 7900);
DISPLAY INVISIBLE (-3225 7900);
FORCEPROP 1 LASTPIN (-3275 7825) $PN 1
J 0
(-3263 7837);
DISPLAY 0.787234 (-3263 7837);
PAINT MONO (-3263 7837);
FORCEPROP 1 LASTPIN (-3075 7825) $PN 2
J 0
(-3113 7837);
DISPLAY 0.787234 (-3113 7837);
PAINT MONO (-3113 7837);
FORCEPROP 1 LAST TOLERANCE 5%
J 0
(-3000 7825);
DISPLAY 0.510638 (-3000 7825);
FORCEPROP 1 LAST MATERIAL EMPTY
J 0
(-3225 7775);
DISPLAY 0.510638 (-3225 7775);
PAINT RED (-3225 7775);
FORCEPROP 1 LAST VALUE 0
J 2
(-3025 7825);
DISPLAY 0.510638 (-3025 7825);
FORCEPROP 0 LAST ROOM NIC_P3V3_BOM1
J 0
(-3475 7900);
DISPLAY 0.680851 (-3475 7900);
PAINT RED (-3475 7900);
FORCEPROP 1 LAST WATTAGE 1/16W
J 2
(-3075 7750);
DISPLAY 0.319149 (-3075 7750);
DISPLAY INVISIBLE (-3075 7750);
FORCEPROP 1 LAST PACK_TYPE 0402LF
J 0
(-2925 7825);
DISPLAY 0.510638 (-2925 7825);
DISPLAY INVISIBLE (-2925 7825);
FORCEPROP 2 LAST CDS_LIB pure_quanta
J 0
(-3175 7825);
DISPLAY INVISIBLE (-3175 7825);
FORCEPROP 1 LAST PATH I122
J 0
(-3225 7975);
DISPLAY 0.978723 (-3225 7975);
PAINT WHITE (-3225 7975);
DISPLAY INVISIBLE (-3225 7975);
FORCEPROP 1 LAST PART_NUMBER CS00002JB13
J 0
(-3250 7775);
DISPLAY 0.319149 (-3250 7775);
DISPLAY INVISIBLE (-3250 7775);
FORCEADD Q_RES..1
(-3250 6350);
FORCEPROP 1 LAST LOCATION R1181
J 0
(-3450 6350);
DISPLAY 0.638298 (-3450 6350);
FORCEPROP 0 LAST $SEC 1
J 0
(-3450 6400);
DISPLAY 0.680851 (-3450 6400);
PAINT MONO (-3450 6400);
DISPLAY INVISIBLE (-3450 6400);
FORCEPROP 0 LAST CDS_SEC 1
J 0
(-3450 6400);
DISPLAY 0.680851 (-3450 6400);
DISPLAY INVISIBLE (-3450 6400);
FORCEPROP 1 LASTPIN (-3350 6350) $PN 1
J 0
(-3338 6362);
DISPLAY 0.787234 (-3338 6362);
PAINT MONO (-3338 6362);
FORCEPROP 1 LASTPIN (-3150 6350) $PN 2
J 0
(-3188 6362);
DISPLAY 0.787234 (-3188 6362);
PAINT MONO (-3188 6362);
FORCEPROP 1 LAST MATERIAL CHIP
J 0
(-3025 6350);
DISPLAY 0.510638 (-3025 6350);
FORCEPROP 1 LAST TOLERANCE 5%
J 0
(-3075 6350);
DISPLAY 0.510638 (-3075 6350);
FORCEPROP 1 LAST VALUE 0
J 2
(-3100 6350);
DISPLAY 0.510638 (-3100 6350);
FORCEPROP 0 LAST ROOM NIC_P12V_MAM_TIC_BOM1
J 0
(-3525 6425);
DISPLAY 0.553191 (-3525 6425);
PAINT RED (-3525 6425);
FORCEPROP 2 LAST CDS_LIB pure_quanta
J 0
(-3250 6350);
DISPLAY INVISIBLE (-3250 6350);
FORCEPROP 1 LAST WATTAGE 1/16W
J 2
(-3150 6275);
DISPLAY 0.319149 (-3150 6275);
DISPLAY INVISIBLE (-3150 6275);
FORCEPROP 1 LAST PACK_TYPE 0402LF
J 0
(-3000 6350);
DISPLAY 0.510638 (-3000 6350);
DISPLAY INVISIBLE (-3000 6350);
FORCEPROP 1 LAST PATH I123
J 0
(-3300 6500);
DISPLAY 0.978723 (-3300 6500);
PAINT WHITE (-3300 6500);
DISPLAY INVISIBLE (-3300 6500);
FORCEPROP 1 LAST PART_NUMBER CS00002JB13
J 0
(-3325 6300);
DISPLAY 0.319149 (-3325 6300);
DISPLAY INVISIBLE (-3325 6300);
FORCEADD OFFPAGE..1
(-4150 6350);
PAINT AQUA (-4150 6350);
FORCEPROP 2 LAST $XR3 248 
J 0
(-4522 6314);
DISPLAY 0.638298 (-4522 6314);
PAINT MONO (-4522 6314);
FORCEPROP 2 LAST $XR2 141 
J 0
(-4402 6314);
DISPLAY 0.638298 (-4402 6314);
PAINT MONO (-4402 6314);
FORCEPROP 2 LAST $XR1 140 
J 0
(-4522 6350);
DISPLAY 0.638298 (-4522 6350);
PAINT MONO (-4522 6350);
FORCEPROP 2 LAST $XR0 142 
J 0
(-4402 6350);
DISPLAY 0.638298 (-4402 6350);
PAINT MONO (-4402 6350);
FORCEPROP 2 LAST CDS_LIB standard
J 0
(-4150 6350);
DISPLAY INVISIBLE (-4150 6350);
FORCEPROP 1 LAST OFFPAGE TRUE
J 0
(-3825 6225);
DISPLAY 0.872340 (-3825 6225);
PAINT AQUA (-3825 6225);
DISPLAY INVISIBLE (-3825 6225);
FORCEPROP 1 LAST COMMENT_BODY TRUE
J 0
(-4025 6250);
DISPLAY 0.872340 (-4025 6250);
PAINT GREEN (-4025 6250);
DISPLAY INVISIBLE (-4025 6250);
FORCEPROP 2 LAST PATH I124
J 0
(-4100 6425);
DISPLAY 0.680851 (-4100 6425);
DISPLAY INVISIBLE (-4100 6425);
FORCEADD OFFPAGE..1
(-4200 8275);
PAINT AQUA (-4200 8275);
FORCEPROP 2 LAST $XR3 248 
J 0
(-4602 8239);
DISPLAY 0.638298 (-4602 8239);
PAINT MONO (-4602 8239);
FORCEPROP 2 LAST $XR2 142 
J 0
(-4482 8239);
DISPLAY 0.638298 (-4482 8239);
PAINT MONO (-4482 8239);
FORCEPROP 2 LAST $XR1 141 
J 0
(-4602 8275);
DISPLAY 0.638298 (-4602 8275);
PAINT MONO (-4602 8275);
FORCEPROP 2 LAST $XR0 140 
J 0
(-4482 8275);
DISPLAY 0.638298 (-4482 8275);
PAINT MONO (-4482 8275);
FORCEPROP 2 LAST CDS_LIB standard
J 0
(-4200 8275);
DISPLAY INVISIBLE (-4200 8275);
FORCEPROP 1 LAST OFFPAGE TRUE
J 0
(-3875 8150);
DISPLAY 0.872340 (-3875 8150);
PAINT AQUA (-3875 8150);
DISPLAY INVISIBLE (-3875 8150);
FORCEPROP 1 LAST COMMENT_BODY TRUE
J 0
(-4075 8175);
DISPLAY 0.872340 (-4075 8175);
PAINT GREEN (-4075 8175);
DISPLAY INVISIBLE (-4075 8175);
FORCEPROP 2 LAST PATH I126
J 0
(-4150 8350);
DISPLAY 0.680851 (-4150 8350);
DISPLAY INVISIBLE (-4150 8350);
FORCEADD Q_RES..1
(3075 8625);
FORCEPROP 1 LAST LOCATION R3832
J 0
(2725 8625);
DISPLAY 0.638298 (2725 8625);
FORCEPROP 0 LAST $SEC 1
J 0
(2725 8675);
DISPLAY 0.680851 (2725 8675);
PAINT MONO (2725 8675);
DISPLAY INVISIBLE (2725 8675);
FORCEPROP 0 LAST CDS_SEC 1
J 0
(2725 8675);
DISPLAY 0.680851 (2725 8675);
DISPLAY INVISIBLE (2725 8675);
FORCEPROP 1 LASTPIN (2975 8625) $PN 1
J 0
(2987 8637);
DISPLAY 0.787234 (2987 8637);
PAINT MONO (2987 8637);
FORCEPROP 1 LASTPIN (3175 8625) $PN 2
J 0
(3137 8637);
DISPLAY 0.787234 (3137 8637);
PAINT MONO (3137 8637);
FORCEPROP 0 LAST ROOM NIC_P3V3_BOM1
J 0
(2875 8550);
DISPLAY 0.553191 (2875 8550);
PAINT RED (2875 8550);
FORCEPROP 1 LAST WATTAGE 1/16W
J 2
(2850 8575);
DISPLAY 0.510638 (2850 8575);
FORCEPROP 1 LAST MATERIAL EMPTY
J 0
(2850 8625);
DISPLAY 0.510638 (2850 8625);
PAINT RED (2850 8625);
FORCEPROP 1 LAST TOLERANCE 5%
J 0
(3250 8625);
DISPLAY 0.510638 (3250 8625);
FORCEPROP 1 LAST VALUE 0
J 2
(3225 8625);
DISPLAY 0.510638 (3225 8625);
FORCEPROP 1 LAST PACK_TYPE 0402LF
J 0
(3225 8575);
DISPLAY 0.510638 (3225 8575);
FORCEPROP 2 LAST CDS_LIB pure_quanta
J 0
(3075 8625);
DISPLAY INVISIBLE (3075 8625);
FORCEPROP 1 LAST PATH I127
J 0
(3025 8775);
DISPLAY 0.978723 (3025 8775);
PAINT WHITE (3025 8775);
DISPLAY INVISIBLE (3025 8775);
FORCEPROP 1 LAST PART_NUMBER CS00002JB13
J 0
(2900 8575);
DISPLAY 0.510638 (2900 8575);
DISPLAY INVISIBLE (2900 8575);
FORCEADD Q_RES..2
(4100 8925);
FORCEPROP 1 LAST LOCATION R3826
J 0
(4145 9050);
DISPLAY 0.638298 (4145 9050);
FORCEPROP 0 LAST $SEC 1
J 0
(4150 9100);
DISPLAY 0.680851 (4150 9100);
PAINT MONO (4150 9100);
DISPLAY INVISIBLE (4150 9100);
FORCEPROP 0 LAST CDS_SEC 1
J 0
(4150 9100);
DISPLAY 0.680851 (4150 9100);
DISPLAY INVISIBLE (4150 9100);
FORCEPROP 1 LASTPIN (4100 9025) $PN 1
J 0
(4105 8987);
DISPLAY 0.787234 (4105 8987);
PAINT MONO (4105 8987);
FORCEPROP 1 LASTPIN (4100 8825) $PN 2
J 0
(4105 8835);
DISPLAY 0.787234 (4105 8835);
PAINT MONO (4105 8835);
FORCEPROP 0 LAST ROOM NIC_P3V3_BOM1
J 0
(4150 9100);
DISPLAY 0.553191 (4150 9100);
PAINT RED (4150 9100);
FORCEPROP 1 LAST PACK_TYPE 0402LF
J 0
(4140 8750);
DISPLAY 0.510638 (4140 8750);
FORCEPROP 1 LAST TOLERANCE 1%
J 0
(4145 8950);
DISPLAY 0.510638 (4145 8950);
FORCEPROP 1 LAST MATERIAL EMPTY
J 0
(4140 8850);
DISPLAY 0.510638 (4140 8850);
PAINT RED (4140 8850);
FORCEPROP 1 LAST WATTAGE 1/16W
J 0
(4140 8900);
DISPLAY 0.510638 (4140 8900);
FORCEPROP 1 LAST VALUE 100K
J 0
(4145 9000);
DISPLAY 0.510638 (4145 9000);
FORCEPROP 2 LAST CDS_LIB pure_quanta
J 0
(4100 8925);
DISPLAY INVISIBLE (4100 8925);
FORCEPROP 1 LAST PATH I128
J 0
(4150 9100);
DISPLAY 0.978723 (4150 9100);
PAINT WHITE (4150 9100);
DISPLAY INVISIBLE (4150 9100);
FORCEPROP 1 LAST PART_NUMBER CS41002FB09
J 0
(4140 8800);
DISPLAY 0.510638 (4140 8800);
DISPLAY INVISIBLE (4140 8800);
FORCEADD Q_RES..1
(-3175 8275);
FORCEPROP 1 LAST LOCATION R1182
J 0
(-3225 8300);
DISPLAY 0.638298 (-3225 8300);
FORCEPROP 0 LAST $SEC 1
J 0
(-3475 8400);
DISPLAY 0.680851 (-3475 8400);
PAINT MONO (-3475 8400);
DISPLAY INVISIBLE (-3475 8400);
FORCEPROP 0 LAST CDS_SEC 1
J 0
(-3475 8400);
DISPLAY 0.680851 (-3475 8400);
DISPLAY INVISIBLE (-3475 8400);
FORCEPROP 1 LASTPIN (-3275 8275) $PN 1
J 0
(-3263 8287);
DISPLAY 0.787234 (-3263 8287);
PAINT MONO (-3263 8287);
FORCEPROP 1 LASTPIN (-3075 8275) $PN 2
J 0
(-3113 8287);
DISPLAY 0.787234 (-3113 8287);
PAINT MONO (-3113 8287);
FORCEPROP 1 LAST MATERIAL EMPTY
J 0
(-3225 8225);
DISPLAY 0.510638 (-3225 8225);
PAINT RED (-3225 8225);
FORCEPROP 1 LAST TOLERANCE 5%
J 0
(-3000 8275);
DISPLAY 0.510638 (-3000 8275);
FORCEPROP 1 LAST VALUE 0
J 2
(-3025 8275);
DISPLAY 0.510638 (-3025 8275);
FORCEPROP 0 LAST ROOM NIC_P3V3_BOM1
J 0
(-3475 8350);
DISPLAY 0.680851 (-3475 8350);
PAINT RED (-3475 8350);
FORCEPROP 2 LAST CDS_LIB pure_quanta
J 0
(-3175 8275);
DISPLAY INVISIBLE (-3175 8275);
FORCEPROP 1 LAST WATTAGE 1/16W
J 2
(-3075 8200);
DISPLAY 0.319149 (-3075 8200);
DISPLAY INVISIBLE (-3075 8200);
FORCEPROP 1 LAST PACK_TYPE 0402LF
J 0
(-2925 8275);
DISPLAY 0.510638 (-2925 8275);
DISPLAY INVISIBLE (-2925 8275);
FORCEPROP 1 LAST PATH I129
J 0
(-3225 8425);
DISPLAY 0.978723 (-3225 8425);
PAINT WHITE (-3225 8425);
DISPLAY INVISIBLE (-3225 8425);
FORCEPROP 1 LAST PART_NUMBER CS00002JB13
J 0
(-3250 8225);
DISPLAY 0.319149 (-3250 8225);
DISPLAY INVISIBLE (-3250 8225);
FORCEADD GND..1
(-2750 5550);
FORCEPROP 3 LASTPIN (-2750 5600) SIG_NAME GND\g
J 0
(-2740 5610);
DISPLAY 0.659574 (-2740 5610);
PAINT MONO (-2740 5610);
DISPLAY INVISIBLE (-2740 5610);
FORCEPROP 1 LAST SIZE 1B
J 0
(-2675 5500);
DISPLAY 0.872340 (-2675 5500);
PAINT GREEN (-2675 5500);
DISPLAY INVISIBLE (-2675 5500);
FORCEPROP 2 LAST CDS_LIB pure_quanta_power
J 0
(-2750 5550);
DISPLAY INVISIBLE (-2750 5550);
FORCEPROP 1 LAST HDL_POWER GND
J 0
(-2750 5700);
DISPLAY 0.872340 (-2750 5700);
PAINT GREEN (-2750 5700);
DISPLAY INVISIBLE (-2750 5700);
FORCEPROP 1 LAST PATH I13
J 0
(-2675 5550);
DISPLAY 0.872340 (-2675 5550);
PAINT AQUA (-2675 5550);
DISPLAY INVISIBLE (-2675 5550);
FORCEADD Q_RES..1
(-3100 8550);
FORCEPROP 1 LAST LOCATION R1520
J 0
(-3150 8600);
DISPLAY 0.978723 (-3150 8600);
FORCEPROP 0 LAST $SEC 1
J 0
(-3275 8725);
DISPLAY 0.680851 (-3275 8725);
PAINT MONO (-3275 8725);
DISPLAY INVISIBLE (-3275 8725);
FORCEPROP 0 LAST CDS_SEC 1
J 0
(-3275 8725);
DISPLAY 0.680851 (-3275 8725);
DISPLAY INVISIBLE (-3275 8725);
FORCEPROP 1 LASTPIN (-3200 8550) $PN 1
J 0
(-3188 8562);
DISPLAY 0.787234 (-3188 8562);
PAINT MONO (-3188 8562);
FORCEPROP 1 LASTPIN (-3000 8550) $PN 2
J 0
(-3038 8562);
DISPLAY 0.787234 (-3038 8562);
PAINT MONO (-3038 8562);
FORCEPROP 0 LAST ROOM NIC_P3V3_BOM1
J 0
(-3275 8675);
DISPLAY 0.680851 (-3275 8675);
PAINT RED (-3275 8675);
FORCEPROP 1 LAST MATERIAL CHIP
J 0
(-2875 8550);
DISPLAY 0.510638 (-2875 8550);
FORCEPROP 1 LAST VALUE 0
J 2
(-2950 8550);
DISPLAY 0.510638 (-2950 8550);
FORCEPROP 1 LAST TOLERANCE 5%
J 0
(-2925 8550);
DISPLAY 0.510638 (-2925 8550);
FORCEPROP 2 LAST CDS_LIB pure_quanta
J 0
(-3100 8550);
DISPLAY INVISIBLE (-3100 8550);
FORCEPROP 1 LAST WATTAGE 1/16W
J 2
(-3000 8475);
DISPLAY 0.319149 (-3000 8475);
DISPLAY INVISIBLE (-3000 8475);
FORCEPROP 1 LAST PACK_TYPE 0402LF
J 0
(-2850 8550);
DISPLAY 0.510638 (-2850 8550);
DISPLAY INVISIBLE (-2850 8550);
FORCEPROP 1 LAST PATH I130
J 0
(-3150 8700);
DISPLAY 0.978723 (-3150 8700);
PAINT WHITE (-3150 8700);
DISPLAY INVISIBLE (-3150 8700);
FORCEPROP 1 LAST PART_NUMBER CS00002JB13
J 0
(-3175 8500);
DISPLAY 0.319149 (-3175 8500);
DISPLAY INVISIBLE (-3175 8500);
FORCEADD OFFPAGE..1
(-4200 8550);
PAINT AQUA (-4200 8550);
FORCEPROP 2 LAST $XR3 248 
J 0
(-4602 8514);
DISPLAY 0.638298 (-4602 8514);
PAINT MONO (-4602 8514);
FORCEPROP 2 LAST $XR2 141 
J 0
(-4482 8514);
DISPLAY 0.638298 (-4482 8514);
PAINT MONO (-4482 8514);
FORCEPROP 2 LAST $XR1 140 
J 0
(-4602 8550);
DISPLAY 0.638298 (-4602 8550);
PAINT MONO (-4602 8550);
FORCEPROP 2 LAST $XR0 142 
J 0
(-4482 8550);
DISPLAY 0.638298 (-4482 8550);
PAINT MONO (-4482 8550);
FORCEPROP 2 LAST CDS_LIB standard
J 0
(-4200 8550);
DISPLAY INVISIBLE (-4200 8550);
FORCEPROP 1 LAST OFFPAGE TRUE
J 0
(-3875 8425);
DISPLAY 0.872340 (-3875 8425);
PAINT AQUA (-3875 8425);
DISPLAY INVISIBLE (-3875 8425);
FORCEPROP 1 LAST COMMENT_BODY TRUE
J 0
(-4075 8450);
DISPLAY 0.872340 (-4075 8450);
PAINT GREEN (-4075 8450);
DISPLAY INVISIBLE (-4075 8450);
FORCEPROP 2 LAST PATH I131
J 0
(-4150 8625);
DISPLAY 0.680851 (-4150 8625);
DISPLAY INVISIBLE (-4150 8625);
FORCEADD Q_RES..2
(-2350 5375);
FORCEPROP 1 LAST LOCATION R3133
J 0
(-2305 5500);
DISPLAY 0.978723 (-2305 5500);
FORCEPROP 0 LAST $SEC 1
J 0
(-2300 5550);
DISPLAY 0.680851 (-2300 5550);
PAINT MONO (-2300 5550);
DISPLAY INVISIBLE (-2300 5550);
FORCEPROP 0 LAST CDS_SEC 1
J 0
(-2300 5550);
DISPLAY 1.021277 (-2300 5550);
DISPLAY INVISIBLE (-2300 5550);
FORCEPROP 1 LASTPIN (-2350 5475) $PN 1
J 0
(-2345 5437);
DISPLAY 0.787234 (-2345 5437);
PAINT MONO (-2345 5437);
FORCEPROP 1 LASTPIN (-2350 5275) $PN 2
J 0
(-2345 5285);
DISPLAY 0.787234 (-2345 5285);
PAINT MONO (-2345 5285);
FORCEPROP 1 LAST TOLERANCE 1%
J 0
(-2305 5400);
DISPLAY 0.638298 (-2305 5400);
FORCEPROP 1 LAST VALUE 1K
J 0
(-2305 5450);
DISPLAY 0.638298 (-2305 5450);
FORCEPROP 1 LAST MATERIAL CHIP
J 0
(-2310 5300);
DISPLAY 0.638298 (-2310 5300);
FORCEPROP 1 LAST WATTAGE 1/16W
J 0
(-2310 5350);
DISPLAY 0.638298 (-2310 5350);
FORCEPROP 1 LAST PACK_TYPE 0402LF
J 0
(-2310 5250);
DISPLAY 0.638298 (-2310 5250);
FORCEPROP 2 LAST CDS_LIB pure_quanta
J 0
(-2350 5375);
DISPLAY INVISIBLE (-2350 5375);
FORCEPROP 1 LAST PATH I14
J 0
(-2300 5550);
DISPLAY 0.978723 (-2300 5550);
PAINT WHITE (-2300 5550);
DISPLAY INVISIBLE (-2300 5550);
FORCEPROP 1 LAST PART_NUMBER CS21002FB06
J 0
(-2310 5250);
DISPLAY 0.638298 (-2310 5250);
DISPLAY INVISIBLE (-2310 5250);
FORCEADD UNIVERSAL_POWER..1
(-2300 5675);
FORCEPROP 3 LASTPIN (-2300 5625) SIG_NAME P3V3_AUX\g
J 0
(-2290 5635);
DISPLAY 0.659574 (-2290 5635);
PAINT MONO (-2290 5635);
DISPLAY INVISIBLE (-2290 5635);
FORCEPROP 1 LAST HDL_POWER P3V3_AUX
J 1
(-2300 5725);
DISPLAY 0.872340 (-2300 5725);
PAINT GREEN (-2300 5725);
FORCEPROP 2 LAST CDS_LIB pure_quanta_power
J 0
(-2300 5675);
DISPLAY INVISIBLE (-2300 5675);
FORCEPROP 1 LAST PATH I15
J 0
(-2250 5700);
DISPLAY 0.872340 (-2250 5700);
PAINT AQUA (-2250 5700);
DISPLAY INVISIBLE (-2250 5700);
FORCEADD Q_RES..2
(-2075 5375);
FORCEPROP 1 LAST LOCATION R3135
J 0
(-2030 5500);
DISPLAY 0.978723 (-2030 5500);
FORCEPROP 0 LAST $SEC 1
J 0
(-2025 5550);
DISPLAY 0.680851 (-2025 5550);
PAINT MONO (-2025 5550);
DISPLAY INVISIBLE (-2025 5550);
FORCEPROP 0 LAST CDS_SEC 1
J 0
(-2025 5550);
DISPLAY 1.021277 (-2025 5550);
DISPLAY INVISIBLE (-2025 5550);
FORCEPROP 1 LASTPIN (-2075 5475) $PN 1
J 0
(-2070 5437);
DISPLAY 0.787234 (-2070 5437);
PAINT MONO (-2070 5437);
FORCEPROP 1 LASTPIN (-2075 5275) $PN 2
J 0
(-2070 5285);
DISPLAY 0.787234 (-2070 5285);
PAINT MONO (-2070 5285);
FORCEPROP 1 LAST MATERIAL CHIP
J 0
(-2035 5300);
DISPLAY 0.638298 (-2035 5300);
FORCEPROP 1 LAST WATTAGE 1/16W
J 0
(-2035 5350);
DISPLAY 0.638298 (-2035 5350);
FORCEPROP 1 LAST TOLERANCE 1%
J 0
(-2030 5400);
DISPLAY 0.638298 (-2030 5400);
FORCEPROP 1 LAST VALUE 1K
J 0
(-2030 5450);
DISPLAY 0.638298 (-2030 5450);
FORCEPROP 1 LAST PACK_TYPE 0402LF
J 0
(-2035 5250);
DISPLAY 0.638298 (-2035 5250);
FORCEPROP 2 LAST CDS_LIB pure_quanta
J 0
(-2075 5375);
DISPLAY INVISIBLE (-2075 5375);
FORCEPROP 1 LAST PATH I16
J 0
(-2025 5550);
DISPLAY 0.978723 (-2025 5550);
PAINT WHITE (-2025 5550);
DISPLAY INVISIBLE (-2025 5550);
FORCEPROP 1 LAST PART_NUMBER CS21002FB06
J 0
(-2035 5250);
DISPLAY 0.638298 (-2035 5250);
DISPLAY INVISIBLE (-2035 5250);
FORCEADD Q_RES..2
(-2750 6475);
FORCEPROP 1 LAST LOCATION R4065
J 0
(-2715 6642);
DISPLAY 0.638298 (-2715 6642);
FORCEPROP 0 LAST $SEC 1
J 0
(-2700 6675);
DISPLAY 0.680851 (-2700 6675);
PAINT MONO (-2700 6675);
DISPLAY INVISIBLE (-2700 6675);
FORCEPROP 0 LAST CDS_SEC 1
J 0
(-2700 6675);
DISPLAY 1.021277 (-2700 6675);
DISPLAY INVISIBLE (-2700 6675);
FORCEPROP 1 LASTPIN (-2750 6575) $PN 1
J 0
(-2745 6537);
DISPLAY 0.787234 (-2745 6537);
PAINT MONO (-2745 6537);
FORCEPROP 1 LASTPIN (-2750 6375) $PN 2
J 0
(-2745 6385);
DISPLAY 0.787234 (-2745 6385);
PAINT MONO (-2745 6385);
FORCEPROP 0 LAST ROOM NIC_P12V_MAM_TIC_BOM1
J 0
(-2700 6725);
DISPLAY 0.553191 (-2700 6725);
PAINT RED (-2700 6725);
FORCEPROP 1 LAST MATERIAL CHIP
J 0
(-2720 6442);
DISPLAY 0.638298 (-2720 6442);
FORCEPROP 1 LAST TOLERANCE 1%
J 0
(-2715 6542);
DISPLAY 0.638298 (-2715 6542);
FORCEPROP 1 LAST WATTAGE 1/16W
J 0
(-2720 6492);
DISPLAY 0.638298 (-2720 6492);
FORCEPROP 1 LAST VALUE 10K
J 0
(-2715 6592);
DISPLAY 0.638298 (-2715 6592);
FORCEPROP 1 LAST PACK_TYPE 0402LF
J 0
(-2720 6342);
DISPLAY 0.638298 (-2720 6342);
FORCEPROP 2 LAST CDS_LIB pure_quanta
J 0
(-2750 6475);
DISPLAY INVISIBLE (-2750 6475);
FORCEPROP 1 LAST PATH I17
J 0
(-2700 6650);
DISPLAY 0.978723 (-2700 6650);
PAINT WHITE (-2700 6650);
DISPLAY INVISIBLE (-2700 6650);
FORCEPROP 1 LAST PART_NUMBER CS31002FB08
J 0
(-2720 6392);
DISPLAY 0.638298 (-2720 6392);
DISPLAY INVISIBLE (-2720 6392);
FORCEADD UNIVERSAL_POWER..1
(-2750 6725);
FORCEPROP 3 LASTPIN (-2750 6675) SIG_NAME P12V_AUX\g
J 0
(-2740 6685);
DISPLAY 0.659574 (-2740 6685);
PAINT MONO (-2740 6685);
DISPLAY INVISIBLE (-2740 6685);
FORCEPROP 1 LAST HDL_POWER P12V_AUX
J 1
(-2750 6775);
DISPLAY 0.872340 (-2750 6775);
PAINT GREEN (-2750 6775);
FORCEPROP 2 LAST CDS_LIB pure_quanta_power
J 0
(-2750 6725);
DISPLAY INVISIBLE (-2750 6725);
FORCEPROP 1 LAST PATH I18
J 0
(-2700 6750);
DISPLAY 0.872340 (-2700 6750);
PAINT AQUA (-2700 6750);
DISPLAY INVISIBLE (-2700 6750);
FORCEADD MOSFET_NCH_DUAL..2
(-1775 6200);
FORCEPROP 1 LAST LOCATION Q118
J 0
(-1624 6176);
DISPLAY 0.723404 (-1624 6176);
PAINT GREEN (-1624 6176);
FORCEPROP 0 LAST $SEC 2
J 0
(-1600 6325);
DISPLAY 0.680851 (-1600 6325);
PAINT MONO (-1600 6325);
DISPLAY INVISIBLE (-1600 6325);
FORCEPROP 0 LAST CDS_SEC 2
J 0
(-1600 6325);
DISPLAY 1.021277 (-1600 6325);
DISPLAY INVISIBLE (-1600 6325);
FORCEPROP 0 LASTPIN (-1725 6400) $PN 3
R 1
J 0
(-1735 6410);
DISPLAY 0.680851 (-1735 6410);
PAINT MONO (-1735 6410);
FORCEPROP 0 LASTPIN (-1975 6150) $PN 5
J 2
(-1985 6160);
DISPLAY 0.680851 (-1985 6160);
PAINT MONO (-1985 6160);
FORCEPROP 0 LASTPIN (-1725 6000) $PN 4
R 1
J 2
(-1735 5990);
DISPLAY 0.680851 (-1735 5990);
PAINT MONO (-1735 5990);
FORCEPROP 1 LAST MATERIAL IC
J 0
(-1624 6051);
DISPLAY 0.723404 (-1624 6051);
PAINT GREEN (-1624 6051);
FORCEPROP 0 LAST ROOM NIC_P12V_MAM_TIC_BOM1
J 0
(-1600 6350);
DISPLAY 0.446809 (-1600 6350);
PAINT RED (-1600 6350);
FORCEPROP 2 LAST PART_TYPE SMLF
J 0
(-1600 6275);
DISPLAY 1.021277 (-1600 6275);
FORCEPROP 2 LAST VALUE PJT138K
J 0
(-1600 6225);
DISPLAY 1.021277 (-1600 6225);
FORCEPROP 2 LAST CDS_LIB pure_quanta
J 0
(-1775 6200);
DISPLAY INVISIBLE (-1775 6200);
FORCEPROP 1 LAST CDS_LMAN_SYM_OUTLINE -150,150,150,-150
J 0
(-1775 6200);
DISPLAY 0.468085 (-1775 6200);
PAINT GREEN (-1775 6200);
DISPLAY INVISIBLE (-1775 6200);
FORCEPROP 1 LAST NEEDS_NO_SIZE TRUE
J 0
(-1625 6091);
DISPLAY 0.468085 (-1625 6091);
PAINT GREEN (-1625 6091);
DISPLAY INVISIBLE (-1625 6091);
FORCEPROP 1 LAST PATH I19
J 0
(-1625 6050);
DISPLAY 0.723404 (-1625 6050);
PAINT GREEN (-1625 6050);
DISPLAY INVISIBLE (-1625 6050);
FORCEPROP 1 LAST PART_NUMBER BAM138K0003
J 0
(-1624 6106);
DISPLAY 0.723404 (-1624 6106);
PAINT GREEN (-1624 6106);
DISPLAY INVISIBLE (-1624 6106);
FORCEADD OFFPAGE..1
(-2700 4125);
FORCEPROP 2 LAST $XR1 143 
J 0
(-3072 4125);
DISPLAY 0.638298 (-3072 4125);
PAINT MONO (-3072 4125);
FORCEPROP 2 LAST $XR0 137 
J 0
(-2952 4125);
DISPLAY 0.638298 (-2952 4125);
PAINT MONO (-2952 4125);
FORCEPROP 2 LAST CDS_LIB standard
J 0
(-2700 4125);
PAINT MONO (-2700 4125);
DISPLAY INVISIBLE (-2700 4125);
FORCEPROP 1 LAST OFFPAGE TRUE
J 0
(-2375 4000);
DISPLAY 0.872340 (-2375 4000);
PAINT GREEN (-2375 4000);
DISPLAY INVISIBLE (-2375 4000);
FORCEPROP 1 LAST COMMENT_BODY TRUE
J 0
(-2575 4025);
DISPLAY 0.872340 (-2575 4025);
PAINT GREEN (-2575 4025);
DISPLAY INVISIBLE (-2575 4025);
FORCEPROP 2 LAST PATH I2
J 0
(-2975 4175);
DISPLAY 0.680851 (-2975 4175);
DISPLAY INVISIBLE (-2975 4175);
FORCEADD GND..1
(-1725 5900);
FORCEPROP 3 LASTPIN (-1725 5950) SIG_NAME GND\g
J 0
(-1715 5960);
DISPLAY 0.659574 (-1715 5960);
PAINT MONO (-1715 5960);
DISPLAY INVISIBLE (-1715 5960);
FORCEPROP 2 LAST CDS_LIB pure_quanta_power
J 0
(-1725 5900);
DISPLAY INVISIBLE (-1725 5900);
FORCEPROP 1 LAST SIZE 1B
J 0
(-1650 5850);
DISPLAY 0.872340 (-1650 5850);
PAINT GREEN (-1650 5850);
DISPLAY INVISIBLE (-1650 5850);
FORCEPROP 1 LAST HDL_POWER GND
J 0
(-1725 6050);
DISPLAY 0.872340 (-1725 6050);
PAINT GREEN (-1725 6050);
DISPLAY INVISIBLE (-1725 6050);
FORCEPROP 1 LAST PATH I20
J 0
(-1650 5900);
DISPLAY 0.872340 (-1650 5900);
PAINT AQUA (-1650 5900);
DISPLAY INVISIBLE (-1650 5900);
FORCEADD UNIVERSAL_GND..1
(-1550 3875);
FORCEPROP 3 LASTPIN (-1550 3925) SIG_NAME GND\g
J 0
(-1540 3935);
DISPLAY 0.659574 (-1540 3935);
PAINT MONO (-1540 3935);
DISPLAY INVISIBLE (-1540 3935);
FORCEPROP 2 LAST CDS_LIB pure_quanta_power
J 0
(-1550 3875);
PAINT MONO (-1550 3875);
DISPLAY INVISIBLE (-1550 3875);
FORCEPROP 1 LAST HDL_POWER GND
J 1
(-1525 3800);
DISPLAY 0.872340 (-1525 3800);
PAINT GREEN (-1525 3800);
DISPLAY INVISIBLE (-1525 3800);
FORCEPROP 1 LAST PATH I21
J 0
(-1475 3875);
DISPLAY 0.872340 (-1475 3875);
PAINT AQUA (-1475 3875);
DISPLAY INVISIBLE (-1475 3875);
FORCEADD 74LVC2G07DW7..1
(-1150 4175);
FORCEPROP 1 LAST LOCATION U59
J 0
(-1319 4556);
DISPLAY 0.723404 (-1319 4556);
PAINT GREEN (-1319 4556);
FORCEPROP 0 LAST $SEC 1
J 0
(-1300 4700);
DISPLAY 0.680851 (-1300 4700);
PAINT MONO (-1300 4700);
DISPLAY INVISIBLE (-1300 4700);
FORCEPROP 0 LAST CDS_SEC 1
J 0
(-1300 4700);
DISPLAY 1.021277 (-1300 4700);
DISPLAY INVISIBLE (-1300 4700);
FORCEPROP 0 LASTPIN (-1475 4225) $PN 1
J 2
(-1485 4235);
DISPLAY 0.680851 (-1485 4235);
PAINT MONO (-1485 4235);
FORCEPROP 0 LASTPIN (-825 4225) $PN 6
J 0
(-815 4235);
DISPLAY 0.680851 (-815 4235);
PAINT MONO (-815 4235);
FORCEPROP 0 LASTPIN (-1475 4125) $PN 3
J 2
(-1485 4135);
DISPLAY 0.680851 (-1485 4135);
PAINT MONO (-1485 4135);
FORCEPROP 0 LASTPIN (-825 4125) $PN 4
J 0
(-815 4135);
DISPLAY 0.680851 (-815 4135);
PAINT MONO (-815 4135);
FORCEPROP 0 LASTPIN (-1475 4175) $PN 2
J 2
(-1485 4185);
DISPLAY 0.680851 (-1485 4185);
PAINT MONO (-1485 4185);
FORCEPROP 0 LASTPIN (-825 4175) $PN 5
J 0
(-815 4185);
DISPLAY 0.680851 (-815 4185);
PAINT MONO (-815 4185);
FORCEPROP 2 LAST VALUE 74LVC2G07DW-7
J 0
(-1300 4600);
DISPLAY 1.021277 (-1300 4600);
FORCEPROP 2 LAST PART_TYPE SMLF
J 0
(-1300 4650);
DISPLAY 1.021277 (-1300 4650);
FORCEPROP 1 LAST MATERIAL IC
J 0
(-1319 4282);
DISPLAY 0.723404 (-1319 4282);
PAINT GREEN (-1319 4282);
FORCEPROP 1 LAST NEEDS_NO_SIZE TRUE
J 0
(-1150 4175);
DISPLAY 0.723404 (-1150 4175);
PAINT GREEN (-1150 4175);
DISPLAY INVISIBLE (-1150 4175);
FORCEPROP 1 LAST CDS_LMAN_SYM_OUTLINE -175,100,175,-100
J 0
(-1150 4175);
DISPLAY 0.468085 (-1150 4175);
PAINT GREEN (-1150 4175);
DISPLAY INVISIBLE (-1150 4175);
FORCEPROP 2 LAST CDS_LIB pure_quanta
J 0
(-1150 4175);
DISPLAY INVISIBLE (-1150 4175);
FORCEPROP 1 LAST PATH I22
J 0
(-1150 4175);
DISPLAY 0.723404 (-1150 4175);
PAINT GREEN (-1150 4175);
DISPLAY INVISIBLE (-1150 4175);
FORCEPROP 1 LAST PART_NUMBER AL002G07003
J 0
(-1319 4409);
DISPLAY 0.723404 (-1319 4409);
PAINT GREEN (-1319 4409);
DISPLAY INVISIBLE (-1319 4409);
FORCEADD Q_CAP..1
(-475 4000);
FORCEPROP 1 LAST LOCATION C1810
J 0
(-425 4100);
DISPLAY 0.978723 (-425 4100);
FORCEPROP 2 LAST $SEC 1
J 0
(-425 4200);
DISPLAY 0.680851 (-425 4200);
PAINT MONO (-425 4200);
DISPLAY INVISIBLE (-425 4200);
FORCEPROP 2 LAST CDS_SEC 1
J 0
(-425 4200);
DISPLAY 1.021277 (-425 4200);
DISPLAY INVISIBLE (-425 4200);
FORCEPROP 1 LASTPIN (-475 4100) $PN 1
J 0
(-465 4080);
DISPLAY 0.787234 (-465 4080);
FORCEPROP 1 LASTPIN (-475 3900) $PN 2
J 0
(-465 3880);
DISPLAY 0.787234 (-465 3880);
FORCEPROP 1 LAST MATERIAL X7R
J 0
(-425 3900);
DISPLAY 0.510638 (-425 3900);
FORCEPROP 1 LAST PACK_TYPE 0402
J 0
(-425 3800);
DISPLAY 0.510638 (-425 3800);
FORCEPROP 1 LAST TOLERANCE 10%
J 0
(-425 3950);
DISPLAY 0.510638 (-425 3950);
FORCEPROP 1 LAST VOLTAGE 25V
J 0
(-425 4000);
DISPLAY 0.510638 (-425 4000);
FORCEPROP 1 LAST VALUE 0.1UF
J 0
(-425 4050);
DISPLAY 0.510638 (-425 4050);
FORCEPROP 2 LAST CDS_LIB pure_quanta
J 0
(-475 4000);
PAINT MONO (-475 4000);
DISPLAY INVISIBLE (-475 4000);
FORCEPROP 1 LAST PATH I23
J 0
(-425 4150);
DISPLAY 0.978723 (-425 4150);
PAINT WHITE (-425 4150);
DISPLAY INVISIBLE (-425 4150);
FORCEPROP 1 LAST PART_NUMBER CH4104K1B00
J 0
(-425 3850);
DISPLAY 0.510638 (-425 3850);
DISPLAY INVISIBLE (-425 3850);
FORCEADD UNIVERSAL_GND..1
(-475 3800);
FORCEPROP 3 LASTPIN (-475 3850) SIG_NAME GND\g
J 0
(-465 3860);
DISPLAY 0.659574 (-465 3860);
PAINT MONO (-465 3860);
DISPLAY INVISIBLE (-465 3860);
FORCEPROP 2 LAST CDS_LIB pure_quanta_power
J 0
(-475 3800);
PAINT MONO (-475 3800);
DISPLAY INVISIBLE (-475 3800);
FORCEPROP 1 LAST HDL_POWER GND
J 1
(-450 3725);
DISPLAY 0.872340 (-450 3725);
PAINT GREEN (-450 3725);
DISPLAY INVISIBLE (-450 3725);
FORCEPROP 1 LAST PATH I24
J 0
(-400 3800);
DISPLAY 0.872340 (-400 3800);
PAINT AQUA (-400 3800);
DISPLAY INVISIBLE (-400 3800);
FORCEADD UNIVERSAL_GND..1
(-475 4700);
FORCEPROP 3 LASTPIN (-475 4750) SIG_NAME GND\g
J 0
(-465 4760);
DISPLAY 0.659574 (-465 4760);
PAINT MONO (-465 4760);
DISPLAY INVISIBLE (-465 4760);
FORCEPROP 2 LAST CDS_LIB pure_quanta_power
J 0
(-475 4700);
PAINT MONO (-475 4700);
DISPLAY INVISIBLE (-475 4700);
FORCEPROP 1 LAST HDL_POWER GND
J 1
(-450 4625);
DISPLAY 0.872340 (-450 4625);
PAINT GREEN (-450 4625);
DISPLAY INVISIBLE (-450 4625);
FORCEPROP 1 LAST PATH I25
J 0
(-400 4700);
DISPLAY 0.872340 (-400 4700);
PAINT AQUA (-400 4700);
DISPLAY INVISIBLE (-400 4700);
FORCEADD UNIVERSAL_POWER..1
(-475 4275);
FORCEPROP 3 LASTPIN (-475 4225) SIG_NAME P3V3_AUX\g
J 0
(-465 4235);
DISPLAY 0.659574 (-465 4235);
PAINT MONO (-465 4235);
DISPLAY INVISIBLE (-465 4235);
FORCEPROP 1 LAST HDL_POWER P3V3_AUX
J 1
(-475 4325);
DISPLAY 0.872340 (-475 4325);
PAINT GREEN (-475 4325);
FORCEPROP 2 LAST CDS_LIB pure_quanta_power
J 0
(-475 4275);
PAINT MONO (-475 4275);
DISPLAY INVISIBLE (-475 4275);
FORCEPROP 1 LAST PATH I26
J 0
(-425 4300);
DISPLAY 0.872340 (-425 4300);
PAINT AQUA (-425 4300);
DISPLAY INVISIBLE (-425 4300);
FORCEADD UNIVERSAL_GND..1
(-1550 4800);
FORCEPROP 3 LASTPIN (-1550 4850) SIG_NAME GND\g
J 0
(-1540 4860);
DISPLAY 0.659574 (-1540 4860);
PAINT MONO (-1540 4860);
DISPLAY INVISIBLE (-1540 4860);
FORCEPROP 2 LAST CDS_LIB pure_quanta_power
J 0
(-1550 4800);
PAINT MONO (-1550 4800);
DISPLAY INVISIBLE (-1550 4800);
FORCEPROP 1 LAST HDL_POWER GND
J 1
(-1525 4725);
DISPLAY 0.872340 (-1525 4725);
PAINT GREEN (-1525 4725);
DISPLAY INVISIBLE (-1525 4725);
FORCEPROP 1 LAST PATH I27
J 0
(-1475 4800);
DISPLAY 0.872340 (-1475 4800);
PAINT AQUA (-1475 4800);
DISPLAY INVISIBLE (-1475 4800);
FORCEADD 74LVC2G07DW7..1
(-1150 5075);
FORCEPROP 1 LAST LOCATION U58
J 0
(-1319 5456);
DISPLAY 0.723404 (-1319 5456);
PAINT GREEN (-1319 5456);
FORCEPROP 0 LAST $SEC 1
J 0
(-1300 5600);
DISPLAY 0.680851 (-1300 5600);
PAINT MONO (-1300 5600);
DISPLAY INVISIBLE (-1300 5600);
FORCEPROP 0 LAST CDS_SEC 1
J 0
(-1300 5600);
DISPLAY 1.021277 (-1300 5600);
DISPLAY INVISIBLE (-1300 5600);
FORCEPROP 0 LASTPIN (-1475 5125) $PN 1
J 2
(-1485 5135);
DISPLAY 0.680851 (-1485 5135);
PAINT MONO (-1485 5135);
FORCEPROP 0 LASTPIN (-825 5125) $PN 6
J 0
(-815 5135);
DISPLAY 0.680851 (-815 5135);
PAINT MONO (-815 5135);
FORCEPROP 0 LASTPIN (-1475 5025) $PN 3
J 2
(-1485 5035);
DISPLAY 0.680851 (-1485 5035);
PAINT MONO (-1485 5035);
FORCEPROP 0 LASTPIN (-825 5025) $PN 4
J 0
(-815 5035);
DISPLAY 0.680851 (-815 5035);
PAINT MONO (-815 5035);
FORCEPROP 0 LASTPIN (-1475 5075) $PN 2
J 2
(-1485 5085);
DISPLAY 0.680851 (-1485 5085);
PAINT MONO (-1485 5085);
FORCEPROP 0 LASTPIN (-825 5075) $PN 5
J 0
(-815 5085);
DISPLAY 0.680851 (-815 5085);
PAINT MONO (-815 5085);
FORCEPROP 2 LAST VALUE 74LVC2G07DW-7
J 0
(-1300 5500);
DISPLAY 1.021277 (-1300 5500);
FORCEPROP 1 LAST MATERIAL IC
J 0
(-1319 5182);
DISPLAY 0.723404 (-1319 5182);
PAINT GREEN (-1319 5182);
FORCEPROP 2 LAST PART_TYPE SMLF
J 0
(-1300 5550);
DISPLAY 1.021277 (-1300 5550);
FORCEPROP 1 LAST NEEDS_NO_SIZE TRUE
J 0
(-1150 5075);
DISPLAY 0.723404 (-1150 5075);
PAINT GREEN (-1150 5075);
DISPLAY INVISIBLE (-1150 5075);
FORCEPROP 1 LAST CDS_LMAN_SYM_OUTLINE -175,100,175,-100
J 0
(-1150 5075);
DISPLAY 0.468085 (-1150 5075);
PAINT GREEN (-1150 5075);
DISPLAY INVISIBLE (-1150 5075);
FORCEPROP 2 LAST CDS_LIB pure_quanta
J 0
(-1150 5075);
DISPLAY INVISIBLE (-1150 5075);
FORCEPROP 1 LAST PATH I28
J 0
(-1150 5075);
DISPLAY 0.723404 (-1150 5075);
PAINT GREEN (-1150 5075);
DISPLAY INVISIBLE (-1150 5075);
FORCEPROP 1 LAST PART_NUMBER AL002G07003
J 0
(-1319 5309);
DISPLAY 0.723404 (-1319 5309);
PAINT GREEN (-1319 5309);
DISPLAY INVISIBLE (-1319 5309);
FORCEADD Q_CAP..1
(-475 4900);
FORCEPROP 1 LAST LOCATION C1809
J 0
(-425 5000);
DISPLAY 0.978723 (-425 5000);
FORCEPROP 2 LAST $SEC 1
J 0
(-425 5100);
DISPLAY 0.680851 (-425 5100);
PAINT MONO (-425 5100);
DISPLAY INVISIBLE (-425 5100);
FORCEPROP 2 LAST CDS_SEC 1
J 0
(-425 5100);
DISPLAY 1.021277 (-425 5100);
DISPLAY INVISIBLE (-425 5100);
FORCEPROP 1 LASTPIN (-475 5000) $PN 1
J 0
(-465 4980);
DISPLAY 0.787234 (-465 4980);
FORCEPROP 1 LASTPIN (-475 4800) $PN 2
J 0
(-465 4780);
DISPLAY 0.787234 (-465 4780);
FORCEPROP 1 LAST TOLERANCE 10%
J 0
(-425 4850);
DISPLAY 0.510638 (-425 4850);
FORCEPROP 1 LAST MATERIAL X7R
J 0
(-425 4800);
DISPLAY 0.510638 (-425 4800);
FORCEPROP 1 LAST PACK_TYPE 0402
J 0
(-425 4700);
DISPLAY 0.510638 (-425 4700);
FORCEPROP 1 LAST VOLTAGE 25V
J 0
(-425 4900);
DISPLAY 0.510638 (-425 4900);
FORCEPROP 1 LAST VALUE 0.1UF
J 0
(-425 4950);
DISPLAY 0.510638 (-425 4950);
FORCEPROP 2 LAST CDS_LIB pure_quanta
J 0
(-475 4900);
PAINT MONO (-475 4900);
DISPLAY INVISIBLE (-475 4900);
FORCEPROP 1 LAST PATH I29
J 0
(-425 5050);
DISPLAY 0.978723 (-425 5050);
PAINT WHITE (-425 5050);
DISPLAY INVISIBLE (-425 5050);
FORCEPROP 1 LAST PART_NUMBER CH4104K1B00
J 0
(-425 4750);
DISPLAY 0.510638 (-425 4750);
DISPLAY INVISIBLE (-425 4750);
FORCEADD OFFPAGE..1
(-2700 4225);
FORCEPROP 2 LAST $XR1 143 
J 0
(-3072 4225);
DISPLAY 0.638298 (-3072 4225);
PAINT MONO (-3072 4225);
FORCEPROP 2 LAST $XR0 137 
J 0
(-2952 4225);
DISPLAY 0.638298 (-2952 4225);
PAINT MONO (-2952 4225);
FORCEPROP 2 LAST CDS_LIB standard
J 0
(-2700 4225);
PAINT MONO (-2700 4225);
DISPLAY INVISIBLE (-2700 4225);
FORCEPROP 1 LAST OFFPAGE TRUE
J 0
(-2375 4100);
DISPLAY 0.872340 (-2375 4100);
PAINT GREEN (-2375 4100);
DISPLAY INVISIBLE (-2375 4100);
FORCEPROP 1 LAST COMMENT_BODY TRUE
J 0
(-2575 4125);
DISPLAY 0.872340 (-2575 4125);
PAINT GREEN (-2575 4125);
DISPLAY INVISIBLE (-2575 4125);
FORCEPROP 2 LAST PATH I3
J 0
(-2975 4275);
DISPLAY 0.680851 (-2975 4275);
DISPLAY INVISIBLE (-2975 4275);
FORCEADD UNIVERSAL_POWER..1
(-475 5175);
FORCEPROP 3 LASTPIN (-475 5125) SIG_NAME P3V3_AUX\g
J 0
(-465 5135);
DISPLAY 0.659574 (-465 5135);
PAINT MONO (-465 5135);
DISPLAY INVISIBLE (-465 5135);
FORCEPROP 1 LAST HDL_POWER P3V3_AUX
J 1
(-475 5225);
DISPLAY 0.872340 (-475 5225);
PAINT GREEN (-475 5225);
FORCEPROP 2 LAST CDS_LIB pure_quanta_power
J 0
(-475 5175);
PAINT MONO (-475 5175);
DISPLAY INVISIBLE (-475 5175);
FORCEPROP 1 LAST PATH I30
J 0
(-425 5200);
DISPLAY 0.872340 (-425 5200);
PAINT AQUA (-425 5200);
DISPLAY INVISIBLE (-425 5200);
FORCEADD Q_RES..2
(-150 5775);
FORCEPROP 1 LAST LOCATION PR3828
J 0
(-100 5850);
DISPLAY 0.638298 (-100 5850);
FORCEPROP 0 LAST $SEC 1
J 0
(-100 5900);
DISPLAY 0.680851 (-100 5900);
PAINT MONO (-100 5900);
DISPLAY INVISIBLE (-100 5900);
FORCEPROP 0 LAST CDS_SEC 1
J 0
(-100 5900);
DISPLAY 1.021277 (-100 5900);
DISPLAY INVISIBLE (-100 5900);
FORCEPROP 1 LASTPIN (-150 5875) $PN 1
J 0
(-145 5837);
DISPLAY 0.787234 (-145 5837);
PAINT MONO (-145 5837);
FORCEPROP 1 LASTPIN (-150 5675) $PN 2
J 0
(-145 5685);
DISPLAY 0.787234 (-145 5685);
PAINT MONO (-145 5685);
FORCEPROP 1 LAST TOLERANCE 1%
J 0
(-100 5800);
DISPLAY 0.404255 (-100 5800);
FORCEPROP 1 LAST PACK_TYPE 0402LF
J 0
(-100 5700);
DISPLAY 0.404255 (-100 5700);
FORCEPROP 1 LAST VALUE 15K
J 0
(-100 5825);
DISPLAY 0.404255 (-100 5825);
FORCEPROP 1 LAST MATERIAL CHIP
J 0
(-100 5750);
DISPLAY 0.404255 (-100 5750);
FORCEPROP 1 LAST WATTAGE 1/16W
J 0
(-100 5775);
DISPLAY 0.404255 (-100 5775);
FORCEPROP 0 LAST ROOM NIC_P12V_MAM_TIC_BOM1
J 0
(-100 5675);
DISPLAY 0.446809 (-100 5675);
PAINT RED (-100 5675);
FORCEPROP 2 LAST CDS_LIB pure_quanta
J 0
(-150 5775);
DISPLAY INVISIBLE (-150 5775);
FORCEPROP 1 LAST PATH I31
J 0
(-100 5950);
DISPLAY 0.978723 (-100 5950);
PAINT WHITE (-100 5950);
DISPLAY INVISIBLE (-100 5950);
FORCEPROP 1 LAST PART_NUMBER CS31502FB05
J 0
(-100 5725);
DISPLAY 0.404255 (-100 5725);
DISPLAY INVISIBLE (-100 5725);
FORCEADD GND..1
(-150 5525);
FORCEPROP 3 LASTPIN (-150 5575) SIG_NAME GND\g
J 0
(-140 5585);
DISPLAY 0.659574 (-140 5585);
PAINT MONO (-140 5585);
DISPLAY INVISIBLE (-140 5585);
FORCEPROP 1 LAST SIZE 1B
J 0
(-75 5475);
DISPLAY 0.872340 (-75 5475);
PAINT GREEN (-75 5475);
DISPLAY INVISIBLE (-75 5475);
FORCEPROP 2 LAST CDS_LIB pure_quanta_power
J 0
(-150 5525);
DISPLAY INVISIBLE (-150 5525);
FORCEPROP 1 LAST HDL_POWER GND
J 0
(-150 5675);
DISPLAY 0.872340 (-150 5675);
PAINT GREEN (-150 5675);
DISPLAY INVISIBLE (-150 5675);
FORCEPROP 1 LAST PATH I32
J 0
(-75 5525);
DISPLAY 0.872340 (-75 5525);
PAINT AQUA (-75 5525);
DISPLAY INVISIBLE (-75 5525);
FORCEADD Q_RES..1
(-750 6400);
FORCEPROP 1 LAST LOCATION R3827
J 0
(-800 6450);
DISPLAY 0.978723 (-800 6450);
FORCEPROP 0 LAST $SEC 1
J 0
(-800 6500);
DISPLAY 0.680851 (-800 6500);
PAINT MONO (-800 6500);
DISPLAY INVISIBLE (-800 6500);
FORCEPROP 0 LAST CDS_SEC 1
J 0
(-800 6500);
DISPLAY 1.021277 (-800 6500);
DISPLAY INVISIBLE (-800 6500);
FORCEPROP 1 LASTPIN (-850 6400) $PN 1
J 0
(-838 6412);
DISPLAY 0.787234 (-838 6412);
PAINT MONO (-838 6412);
FORCEPROP 1 LASTPIN (-650 6400) $PN 2
J 0
(-688 6412);
DISPLAY 0.787234 (-688 6412);
PAINT MONO (-688 6412);
FORCEPROP 0 LAST ROOM NIC_P12V_MAM_TIC_BOM1
J 0
(-900 6300);
DISPLAY 0.446809 (-900 6300);
PAINT RED (-900 6300);
FORCEPROP 1 LAST VALUE 0
J 2
(-600 6400);
DISPLAY 0.510638 (-600 6400);
FORCEPROP 1 LAST TOLERANCE 5%
J 0
(-575 6400);
DISPLAY 0.510638 (-575 6400);
FORCEPROP 1 LAST WATTAGE 1/16W
J 2
(-550 6325);
DISPLAY 0.510638 (-550 6325);
FORCEPROP 1 LAST MATERIAL CHIP
J 0
(-825 6325);
DISPLAY 0.510638 (-825 6325);
FORCEPROP 1 LAST PACK_TYPE 0402LF
J 0
(-475 6400);
DISPLAY 0.510638 (-475 6400);
FORCEPROP 2 LAST CDS_LIB pure_quanta
J 0
(-750 6400);
DISPLAY INVISIBLE (-750 6400);
FORCEPROP 1 LAST PATH I33
J 0
(-800 6550);
DISPLAY 0.978723 (-800 6550);
PAINT WHITE (-800 6550);
DISPLAY INVISIBLE (-800 6550);
FORCEPROP 1 LAST PART_NUMBER CS00002JB13
J 0
(-825 6350);
DISPLAY 0.510638 (-825 6350);
DISPLAY INVISIBLE (-825 6350);
FORCEADD GND..1
(-725 6650);
FORCEPROP 3 LASTPIN (-725 6700) SIG_NAME GND\g
J 0
(-715 6710);
DISPLAY 0.659574 (-715 6710);
PAINT MONO (-715 6710);
DISPLAY INVISIBLE (-715 6710);
FORCEPROP 2 LAST CDS_LIB pure_quanta_power
J 0
(-725 6650);
DISPLAY INVISIBLE (-725 6650);
FORCEPROP 1 LAST SIZE 1B
J 0
(-650 6600);
DISPLAY 0.872340 (-650 6600);
PAINT GREEN (-650 6600);
DISPLAY INVISIBLE (-650 6600);
FORCEPROP 1 LAST HDL_POWER GND
J 0
(-725 6800);
DISPLAY 0.872340 (-725 6800);
PAINT GREEN (-725 6800);
DISPLAY INVISIBLE (-725 6800);
FORCEPROP 1 LAST PATH I34
J 0
(-650 6650);
DISPLAY 0.872340 (-650 6650);
PAINT AQUA (-650 6650);
DISPLAY INVISIBLE (-650 6650);
FORCEADD Q_RES..2
(-150 6050);
FORCEPROP 1 LAST LOCATION PR3806
J 0
(-100 6125);
DISPLAY 0.638298 (-100 6125);
FORCEPROP 0 LAST $SEC 1
J 0
(-100 6175);
DISPLAY 0.680851 (-100 6175);
PAINT MONO (-100 6175);
DISPLAY INVISIBLE (-100 6175);
FORCEPROP 0 LAST CDS_SEC 1
J 0
(-100 6175);
DISPLAY 1.021277 (-100 6175);
DISPLAY INVISIBLE (-100 6175);
FORCEPROP 1 LASTPIN (-150 6150) $PN 1
J 0
(-145 6112);
DISPLAY 0.787234 (-145 6112);
PAINT MONO (-145 6112);
FORCEPROP 1 LASTPIN (-150 5950) $PN 2
J 0
(-145 5960);
DISPLAY 0.787234 (-145 5960);
PAINT MONO (-145 5960);
FORCEPROP 0 LAST ROOM NIC_P12V_MAM_TIC_BOM1
J 0
(-600 5950);
DISPLAY 0.446809 (-600 5950);
PAINT RED (-600 5950);
FORCEPROP 1 LAST TOLERANCE 1%
J 0
(-100 6075);
DISPLAY 0.404255 (-100 6075);
FORCEPROP 1 LAST PACK_TYPE 0402LF
J 0
(-100 5975);
DISPLAY 0.404255 (-100 5975);
FORCEPROP 1 LAST MATERIAL CHIP
J 0
(-100 6025);
DISPLAY 0.404255 (-100 6025);
FORCEPROP 1 LAST WATTAGE 1/16W
J 0
(-100 6050);
DISPLAY 0.404255 (-100 6050);
FORCEPROP 1 LAST VALUE 6.8K
J 0
(-100 6100);
DISPLAY 0.404255 (-100 6100);
FORCEPROP 2 LAST CDS_LIB pure_quanta
J 0
(-150 6050);
DISPLAY INVISIBLE (-150 6050);
FORCEPROP 1 LAST PATH I35
J 0
(-100 6225);
DISPLAY 0.978723 (-100 6225);
PAINT WHITE (-100 6225);
DISPLAY INVISIBLE (-100 6225);
FORCEPROP 1 LAST PART_NUMBER CS26802FB02
J 0
(-100 6000);
DISPLAY 0.404255 (-100 6000);
DISPLAY INVISIBLE (-100 6000);
FORCEADD Q_RES..2
(-150 6725);
FORCEPROP 1 LAST LOCATION PR3805
J 0
(-100 6800);
DISPLAY 0.638298 (-100 6800);
FORCEPROP 0 LAST $SEC 1
J 0
(-100 6850);
DISPLAY 0.680851 (-100 6850);
PAINT MONO (-100 6850);
DISPLAY INVISIBLE (-100 6850);
FORCEPROP 0 LAST CDS_SEC 1
J 0
(-100 6850);
DISPLAY 1.021277 (-100 6850);
DISPLAY INVISIBLE (-100 6850);
FORCEPROP 1 LASTPIN (-150 6825) $PN 1
J 0
(-145 6787);
DISPLAY 0.787234 (-145 6787);
PAINT MONO (-145 6787);
FORCEPROP 1 LASTPIN (-150 6625) $PN 2
J 0
(-145 6635);
DISPLAY 0.787234 (-145 6635);
PAINT MONO (-145 6635);
FORCEPROP 0 LAST ROOM NIC_P12V_MAM_TIC_BOM1
J 0
(-175 6850);
DISPLAY 0.297872 (-175 6850);
PAINT RED (-175 6850);
FORCEPROP 1 LAST VALUE 160K
J 0
(-100 6775);
DISPLAY 0.404255 (-100 6775);
FORCEPROP 1 LAST TOLERANCE 1%
J 0
(-100 6750);
DISPLAY 0.404255 (-100 6750);
FORCEPROP 1 LAST PACK_TYPE 0402LF
J 0
(-100 6650);
DISPLAY 0.404255 (-100 6650);
FORCEPROP 1 LAST WATTAGE 1/16W
J 0
(-100 6725);
DISPLAY 0.404255 (-100 6725);
FORCEPROP 1 LAST MATERIAL CHIP
J 0
(-100 6700);
DISPLAY 0.404255 (-100 6700);
FORCEPROP 2 LAST CDS_LIB pure_quanta
J 0
(-150 6725);
DISPLAY INVISIBLE (-150 6725);
FORCEPROP 1 LAST PATH I36
J 0
(-100 6900);
DISPLAY 0.978723 (-100 6900);
PAINT WHITE (-100 6900);
DISPLAY INVISIBLE (-100 6900);
FORCEPROP 1 LAST PART_NUMBER CS41602FB05
J 0
(-100 6675);
DISPLAY 0.404255 (-100 6675);
DISPLAY INVISIBLE (-100 6675);
FORCEADD OFFPAGE..1
(-4125 7825);
PAINT AQUA (-4125 7825);
FORCEPROP 2 LAST $XR3 248 
J 0
(-4436 7789);
DISPLAY 0.638298 (-4436 7789);
PAINT MONO (-4436 7789);
FORCEPROP 2 LAST $XR2 141 
J 0
(-4556 7825);
DISPLAY 0.638298 (-4556 7825);
PAINT MONO (-4556 7825);
FORCEPROP 2 LAST $XR1 83 
J 0
(-4436 7825);
DISPLAY 0.638298 (-4436 7825);
PAINT MONO (-4436 7825);
FORCEPROP 2 LAST $XR0 81 
J 0
(-4346 7825);
DISPLAY 0.638298 (-4346 7825);
PAINT MONO (-4346 7825);
FORCEPROP 2 LAST CDS_LIB standard
J 0
(-4125 7825);
DISPLAY INVISIBLE (-4125 7825);
FORCEPROP 1 LAST OFFPAGE TRUE
J 0
(-3800 7700);
DISPLAY 0.872340 (-3800 7700);
PAINT AQUA (-3800 7700);
DISPLAY INVISIBLE (-3800 7700);
FORCEPROP 1 LAST COMMENT_BODY TRUE
J 0
(-4000 7725);
DISPLAY 0.872340 (-4000 7725);
PAINT GREEN (-4000 7725);
DISPLAY INVISIBLE (-4000 7725);
FORCEPROP 2 LAST PATH I37
J 0
(-4375 7875);
DISPLAY 0.680851 (-4375 7875);
DISPLAY INVISIBLE (-4375 7875);
FORCEADD GND..1
(-2725 7275);
FORCEPROP 3 LASTPIN (-2725 7325) SIG_NAME GND\g
J 0
(-2715 7335);
DISPLAY 0.659574 (-2715 7335);
PAINT MONO (-2715 7335);
DISPLAY INVISIBLE (-2715 7335);
FORCEPROP 1 LAST SIZE 1B
J 0
(-2650 7225);
DISPLAY 0.872340 (-2650 7225);
PAINT GREEN (-2650 7225);
DISPLAY INVISIBLE (-2650 7225);
FORCEPROP 2 LAST CDS_LIB pure_quanta_power
J 0
(-2725 7275);
DISPLAY INVISIBLE (-2725 7275);
FORCEPROP 1 LAST HDL_POWER GND
J 0
(-2725 7425);
DISPLAY 0.872340 (-2725 7425);
PAINT GREEN (-2725 7425);
DISPLAY INVISIBLE (-2725 7425);
FORCEPROP 1 LAST PATH I39
J 0
(-2650 7275);
DISPLAY 0.872340 (-2650 7275);
PAINT AQUA (-2650 7275);
DISPLAY INVISIBLE (-2650 7275);
FORCEADD Q_RES..2
(-2525 4475);
FORCEPROP 1 LAST LOCATION R3134
J 0
(-2480 4600);
DISPLAY 0.978723 (-2480 4600);
FORCEPROP 0 LAST $SEC 1
J 0
(-2475 4650);
DISPLAY 0.680851 (-2475 4650);
PAINT MONO (-2475 4650);
DISPLAY INVISIBLE (-2475 4650);
FORCEPROP 0 LAST CDS_SEC 1
J 0
(-2475 4650);
DISPLAY 1.021277 (-2475 4650);
DISPLAY INVISIBLE (-2475 4650);
FORCEPROP 1 LASTPIN (-2525 4575) $PN 1
J 0
(-2520 4537);
DISPLAY 0.787234 (-2520 4537);
PAINT MONO (-2520 4537);
FORCEPROP 1 LASTPIN (-2525 4375) $PN 2
J 0
(-2520 4385);
DISPLAY 0.787234 (-2520 4385);
PAINT MONO (-2520 4385);
FORCEPROP 1 LAST WATTAGE 1/16W
J 0
(-2485 4450);
DISPLAY 0.638298 (-2485 4450);
FORCEPROP 1 LAST TOLERANCE 1%
J 0
(-2480 4500);
DISPLAY 0.638298 (-2480 4500);
FORCEPROP 1 LAST VALUE 1K
J 0
(-2480 4550);
DISPLAY 0.638298 (-2480 4550);
FORCEPROP 1 LAST MATERIAL CHIP
J 0
(-2485 4400);
DISPLAY 0.638298 (-2485 4400);
FORCEPROP 1 LAST PACK_TYPE 0402LF
J 0
(-2485 4350);
DISPLAY 0.638298 (-2485 4350);
FORCEPROP 2 LAST CDS_LIB pure_quanta
J 0
(-2525 4475);
DISPLAY INVISIBLE (-2525 4475);
FORCEPROP 1 LAST PATH I4
J 0
(-2475 4650);
DISPLAY 0.978723 (-2475 4650);
PAINT WHITE (-2475 4650);
DISPLAY INVISIBLE (-2475 4650);
FORCEPROP 1 LAST PART_NUMBER CS21002FB06
J 0
(-2485 4350);
DISPLAY 0.638298 (-2485 4350);
DISPLAY INVISIBLE (-2485 4350);
FORCEADD GND..1
(-2225 7525);
FORCEPROP 3 LASTPIN (-2225 7575) SIG_NAME GND\g
J 0
(-2215 7585);
DISPLAY 0.659574 (-2215 7585);
PAINT MONO (-2215 7585);
DISPLAY INVISIBLE (-2215 7585);
FORCEPROP 2 LAST CDS_LIB pure_quanta_power
J 0
(-2225 7525);
DISPLAY INVISIBLE (-2225 7525);
FORCEPROP 1 LAST SIZE 1B
J 0
(-2150 7475);
DISPLAY 0.872340 (-2150 7475);
PAINT GREEN (-2150 7475);
DISPLAY INVISIBLE (-2150 7475);
FORCEPROP 1 LAST HDL_POWER GND
J 0
(-2225 7675);
DISPLAY 0.872340 (-2225 7675);
PAINT GREEN (-2225 7675);
DISPLAY INVISIBLE (-2225 7675);
FORCEPROP 1 LAST PATH I41
J 0
(-2150 7525);
DISPLAY 0.872340 (-2150 7525);
PAINT AQUA (-2150 7525);
DISPLAY INVISIBLE (-2150 7525);
FORCEADD MOSFET_NCH_DUAL..1
(-2275 7875);
FORCEPROP 1 LAST LOCATION Q119
J 0
(-2124 7849);
DISPLAY 0.723404 (-2124 7849);
PAINT GREEN (-2124 7849);
FORCEPROP 0 LAST $SEC 1
J 0
(-2100 8000);
DISPLAY 0.680851 (-2100 8000);
PAINT MONO (-2100 8000);
DISPLAY INVISIBLE (-2100 8000);
FORCEPROP 0 LAST CDS_SEC 1
J 0
(-2100 8000);
DISPLAY 1.021277 (-2100 8000);
DISPLAY INVISIBLE (-2100 8000);
FORCEPROP 0 LASTPIN (-2225 8075) $PN 6
R 1
J 0
(-2235 8085);
DISPLAY 0.680851 (-2235 8085);
PAINT MONO (-2235 8085);
FORCEPROP 0 LASTPIN (-2475 7825) $PN 2
J 2
(-2485 7835);
DISPLAY 0.680851 (-2485 7835);
PAINT MONO (-2485 7835);
FORCEPROP 0 LASTPIN (-2225 7675) $PN 1
R 1
J 2
(-2235 7665);
DISPLAY 0.680851 (-2235 7665);
PAINT MONO (-2235 7665);
FORCEPROP 2 LAST VALUE PJT138K
J 0
(-2100 7900);
DISPLAY 1.021277 (-2100 7900);
FORCEPROP 1 LAST MATERIAL IC
J 0
(-2124 7724);
DISPLAY 0.723404 (-2124 7724);
PAINT GREEN (-2124 7724);
FORCEPROP 2 LAST PART_TYPE SMLF
J 0
(-2100 7950);
DISPLAY 1.021277 (-2100 7950);
FORCEPROP 0 LAST ROOM NIC_P3V3_BOM1
J 0
(-2100 8050);
DISPLAY 0.680851 (-2100 8050);
PAINT RED (-2100 8050);
FORCEPROP 1 LAST NEEDS_NO_SIZE TRUE
J 0
(-2275 7874);
DISPLAY 0.468085 (-2275 7874);
PAINT GREEN (-2275 7874);
DISPLAY INVISIBLE (-2275 7874);
FORCEPROP 1 LAST CDS_LMAN_SYM_OUTLINE -150,150,150,-150
J 0
(-2275 7875);
DISPLAY 0.468085 (-2275 7875);
PAINT GREEN (-2275 7875);
DISPLAY INVISIBLE (-2275 7875);
FORCEPROP 2 LAST CDS_LIB pure_quanta
J 0
(-2275 7875);
DISPLAY INVISIBLE (-2275 7875);
FORCEPROP 1 LAST PATH I42
J 0
(-2275 7875);
DISPLAY 0.723404 (-2275 7875);
PAINT GREEN (-2275 7875);
DISPLAY INVISIBLE (-2275 7875);
FORCEPROP 1 LAST PART_NUMBER BAM138K0003
J 0
(-2124 7789);
DISPLAY 0.723404 (-2124 7789);
PAINT GREEN (-2124 7789);
DISPLAY INVISIBLE (-2124 7789);
FORCEADD Q_RES..2
(-2225 8475);
FORCEPROP 1 LAST LOCATION R4067
J 0
(-2190 8642);
DISPLAY 0.638298 (-2190 8642);
FORCEPROP 0 LAST $SEC 1
J 0
(-2175 8675);
DISPLAY 0.680851 (-2175 8675);
PAINT MONO (-2175 8675);
DISPLAY INVISIBLE (-2175 8675);
FORCEPROP 0 LAST CDS_SEC 1
J 0
(-2175 8675);
DISPLAY 1.021277 (-2175 8675);
DISPLAY INVISIBLE (-2175 8675);
FORCEPROP 1 LASTPIN (-2225 8575) $PN 1
J 0
(-2220 8537);
DISPLAY 0.787234 (-2220 8537);
PAINT MONO (-2220 8537);
FORCEPROP 1 LASTPIN (-2225 8375) $PN 2
J 0
(-2220 8385);
DISPLAY 0.787234 (-2220 8385);
PAINT MONO (-2220 8385);
FORCEPROP 1 LAST VALUE 10K
J 0
(-2190 8592);
DISPLAY 0.638298 (-2190 8592);
FORCEPROP 1 LAST WATTAGE 1/16W
J 0
(-2195 8492);
DISPLAY 0.638298 (-2195 8492);
FORCEPROP 1 LAST PACK_TYPE 0402LF
J 0
(-2195 8342);
DISPLAY 0.638298 (-2195 8342);
FORCEPROP 0 LAST ROOM NIC_P3V3_BOM1
J 0
(-2175 8725);
DISPLAY 0.680851 (-2175 8725);
PAINT RED (-2175 8725);
FORCEPROP 1 LAST TOLERANCE 1%
J 0
(-2190 8542);
DISPLAY 0.638298 (-2190 8542);
FORCEPROP 1 LAST MATERIAL CHIP
J 0
(-2195 8442);
DISPLAY 0.638298 (-2195 8442);
FORCEPROP 2 LAST CDS_LIB pure_quanta
J 0
(-2225 8475);
DISPLAY INVISIBLE (-2225 8475);
FORCEPROP 1 LAST PATH I43
J 0
(-2175 8650);
DISPLAY 0.978723 (-2175 8650);
PAINT WHITE (-2175 8650);
DISPLAY INVISIBLE (-2175 8650);
FORCEPROP 1 LAST PART_NUMBER CS31002FB08
J 0
(-2195 8392);
DISPLAY 0.638298 (-2195 8392);
DISPLAY INVISIBLE (-2195 8392);
FORCEADD UNIVERSAL_POWER..1
(-2225 8725);
FORCEPROP 3 LASTPIN (-2225 8675) SIG_NAME P12V_AUX\g
J 0
(-2215 8685);
DISPLAY 0.659574 (-2215 8685);
PAINT MONO (-2215 8685);
DISPLAY INVISIBLE (-2215 8685);
FORCEPROP 1 LAST HDL_POWER P12V_AUX
J 1
(-2225 8775);
DISPLAY 0.872340 (-2225 8775);
PAINT GREEN (-2225 8775);
FORCEPROP 2 LAST CDS_LIB pure_quanta_power
J 0
(-2225 8725);
DISPLAY INVISIBLE (-2225 8725);
FORCEPROP 1 LAST PATH I44
J 0
(-2175 8750);
DISPLAY 0.872340 (-2175 8750);
PAINT AQUA (-2175 8750);
DISPLAY INVISIBLE (-2175 8750);
FORCEADD MOSFET_NCH_DUAL..2
(-1575 8250);
FORCEPROP 1 LAST LOCATION Q119
J 0
(-1424 8226);
DISPLAY 0.723404 (-1424 8226);
PAINT GREEN (-1424 8226);
FORCEPROP 0 LAST $SEC 2
J 0
(-1400 8375);
DISPLAY 0.680851 (-1400 8375);
PAINT MONO (-1400 8375);
DISPLAY INVISIBLE (-1400 8375);
FORCEPROP 0 LAST CDS_SEC 2
J 0
(-1400 8375);
DISPLAY 1.021277 (-1400 8375);
DISPLAY INVISIBLE (-1400 8375);
FORCEPROP 0 LASTPIN (-1525 8450) $PN 3
R 1
J 0
(-1535 8460);
DISPLAY 0.680851 (-1535 8460);
PAINT MONO (-1535 8460);
FORCEPROP 0 LASTPIN (-1775 8200) $PN 5
J 2
(-1785 8210);
DISPLAY 0.680851 (-1785 8210);
PAINT MONO (-1785 8210);
FORCEPROP 0 LASTPIN (-1525 8050) $PN 4
R 1
J 2
(-1535 8040);
DISPLAY 0.680851 (-1535 8040);
PAINT MONO (-1535 8040);
FORCEPROP 2 LAST PART_TYPE SMLF
J 0
(-1400 8325);
DISPLAY 1.021277 (-1400 8325);
FORCEPROP 1 LAST MATERIAL IC
J 0
(-1424 8101);
DISPLAY 0.723404 (-1424 8101);
PAINT GREEN (-1424 8101);
FORCEPROP 2 LAST VALUE PJT138K
J 0
(-1400 8275);
DISPLAY 1.021277 (-1400 8275);
FORCEPROP 0 LAST ROOM NIC_P3V3_BOM1
J 0
(-1400 8425);
DISPLAY 0.680851 (-1400 8425);
PAINT RED (-1400 8425);
FORCEPROP 1 LAST NEEDS_NO_SIZE TRUE
J 0
(-1425 8141);
DISPLAY 0.468085 (-1425 8141);
PAINT GREEN (-1425 8141);
DISPLAY INVISIBLE (-1425 8141);
FORCEPROP 1 LAST CDS_LMAN_SYM_OUTLINE -150,150,150,-150
J 0
(-1575 8250);
DISPLAY 0.468085 (-1575 8250);
PAINT GREEN (-1575 8250);
DISPLAY INVISIBLE (-1575 8250);
FORCEPROP 2 LAST CDS_LIB pure_quanta
J 0
(-1575 8250);
DISPLAY INVISIBLE (-1575 8250);
FORCEPROP 1 LAST PATH I45
J 0
(-1425 8100);
DISPLAY 0.723404 (-1425 8100);
PAINT GREEN (-1425 8100);
DISPLAY INVISIBLE (-1425 8100);
FORCEPROP 1 LAST PART_NUMBER BAM138K0003
J 0
(-1424 8156);
DISPLAY 0.723404 (-1424 8156);
PAINT GREEN (-1424 8156);
DISPLAY INVISIBLE (-1424 8156);
FORCEADD GND..1
(-1525 7900);
FORCEPROP 3 LASTPIN (-1525 7950) SIG_NAME GND\g
J 0
(-1515 7960);
DISPLAY 0.659574 (-1515 7960);
PAINT MONO (-1515 7960);
DISPLAY INVISIBLE (-1515 7960);
FORCEPROP 2 LAST CDS_LIB pure_quanta_power
J 0
(-1525 7900);
DISPLAY INVISIBLE (-1525 7900);
FORCEPROP 1 LAST SIZE 1B
J 0
(-1450 7850);
DISPLAY 0.872340 (-1450 7850);
PAINT GREEN (-1450 7850);
DISPLAY INVISIBLE (-1450 7850);
FORCEPROP 1 LAST HDL_POWER GND
J 0
(-1525 8050);
DISPLAY 0.872340 (-1525 8050);
PAINT GREEN (-1525 8050);
DISPLAY INVISIBLE (-1525 8050);
FORCEPROP 1 LAST PATH I46
J 0
(-1450 7900);
DISPLAY 0.872340 (-1450 7900);
PAINT AQUA (-1450 7900);
DISPLAY INVISIBLE (-1450 7900);
FORCEADD DIODE_TVS..1
R 1
(-875 7025);
FORCEPROP 1 LAST LOCATION PD107
J 0
(-820 7067);
DISPLAY 0.574468 (-820 7067);
PAINT GREEN (-820 7067);
FORCEPROP 0 LAST $SEC 1
R 1
J 0
(-820 7117);
DISPLAY INVISIBLE (-820 7117);
FORCEPROP 0 LAST CDS_SEC 1
R 1
J 0
(-820 7117);
DISPLAY INVISIBLE (-820 7117);
FORCEPROP 0 LASTPIN (-875 6875) $PN A
R 1
J 2
(-885 6865);
DISPLAY 0.808511 (-885 6865);
FORCEPROP 0 LASTPIN (-875 7175) $PN C
R 1
J 0
(-885 7185);
DISPLAY 0.808511 (-885 7185);
FORCEPROP 1 LAST MATERIAL IC
J 0
(-800 6900);
DISPLAY 0.723404 (-800 6900);
PAINT GREEN (-800 6900);
FORCEPROP 2 LAST VALUE SMF14A
J 0
(-825 7000);
DISPLAY 0.574468 (-825 7000);
PAINT SKYBLUE (-825 7000);
FORCEPROP 2 LAST CDS_LIB pure_quanta
J 0
(-875 7025);
DISPLAY INVISIBLE (-875 7025);
FORCEPROP 1 LAST CDS_LMAN_SYM_OUTLINE -100,50,100,-50
R 1
J 0
(-875 7025);
DISPLAY 0.468085 (-875 7025);
PAINT GREEN (-875 7025);
DISPLAY INVISIBLE (-875 7025);
FORCEPROP 1 LASTPIN (-875 7175) Pin_Length Short
R 1
J 0
(-865 7200);
DISPLAY 0.489362 (-865 7200);
PAINT MONO (-865 7200);
DISPLAY INVISIBLE (-865 7200);
FORCEPROP 0 LAST PART_TYPE SMLF
J 0
(-775 7150);
DISPLAY 1.021277 (-775 7150);
DISPLAY INVISIBLE (-775 7150);
FORCEPROP 1 LAST PIN_NAMES_ROTATE True
R 1
J 0
(-875 7025);
DISPLAY 0.489362 (-875 7025);
PAINT GREEN (-875 7025);
DISPLAY INVISIBLE (-875 7025);
FORCEPROP 1 LAST PATH I47
R 1
J 0
(-825 7125);
DISPLAY 0.723404 (-825 7125);
PAINT GREEN (-825 7125);
DISPLAY INVISIBLE (-825 7125);
FORCEPROP 1 LAST PART_NUMBER BCSMF14AZ01
J 0
(-820 6942);
DISPLAY 0.574468 (-820 6942);
PAINT GREEN (-820 6942);
DISPLAY INVISIBLE (-820 6942);
FORCEADD UNIVERSAL_POWER..1
(-725 7375);
FORCEPROP 3 LASTPIN (-725 7325) SIG_NAME P12V_AUX\g
J 0
(-715 7335);
DISPLAY 0.659574 (-715 7335);
PAINT MONO (-715 7335);
DISPLAY INVISIBLE (-715 7335);
FORCEPROP 1 LAST HDL_POWER P12V_AUX
J 1
(-725 7425);
DISPLAY 0.872340 (-725 7425);
PAINT GREEN (-725 7425);
FORCEPROP 2 LAST CDS_LIB pure_quanta_power
J 0
(-725 7375);
DISPLAY INVISIBLE (-725 7375);
FORCEPROP 1 LAST PATH I48
J 0
(-675 7400);
DISPLAY 0.872340 (-675 7400);
PAINT AQUA (-675 7400);
DISPLAY INVISIBLE (-675 7400);
FORCEADD Q_CAP..1
(-500 7025);
FORCEPROP 1 LAST LOCATION PC2139
J 0
(-450 7100);
DISPLAY 0.638298 (-450 7100);
FORCEPROP 0 LAST $SEC 1
J 0
(-445 7167);
DISPLAY INVISIBLE (-445 7167);
FORCEPROP 0 LAST CDS_SEC 1
J 0
(-445 7167);
DISPLAY INVISIBLE (-445 7167);
FORCEPROP 1 LASTPIN (-500 7125) $PN 1
J 0
(-490 7105);
DISPLAY 0.787234 (-490 7105);
PAINT MONO (-490 7105);
DISPLAY INVISIBLE (-490 7105);
FORCEPROP 1 LASTPIN (-500 6925) $PN 2
J 0
(-490 6905);
DISPLAY 0.787234 (-490 6905);
PAINT MONO (-490 6905);
DISPLAY INVISIBLE (-490 6905);
FORCEPROP 1 LAST MATERIAL X6S
J 0
(-450 7025);
DISPLAY 0.510638 (-450 7025);
FORCEPROP 1 LAST VOLTAGE 25V
J 0
(-450 7050);
DISPLAY 0.510638 (-450 7050);
FORCEPROP 1 LAST VALUE 1UF
J 0
(-450 7075);
DISPLAY 0.510638 (-450 7075);
FORCEPROP 1 LAST PACK_TYPE C0402
J 0
(-450 7000);
DISPLAY 0.510638 (-450 7000);
FORCEPROP 1 LAST TOLERANCE 10%
J 0
(-450 6975);
DISPLAY 0.638298 (-450 6975);
DISPLAY INVISIBLE (-450 6975);
FORCEPROP 2 LAST CDS_LIB pure_quanta
J 0
(-500 7025);
DISPLAY INVISIBLE (-500 7025);
FORCEPROP 1 LAST PATH I49
J 0
(-450 7175);
DISPLAY 0.978723 (-450 7175);
PAINT WHITE (-450 7175);
DISPLAY INVISIBLE (-450 7175);
FORCEPROP 1 LAST PART_NUMBER CH5104KEB02
J 0
(-450 6975);
DISPLAY 0.510638 (-450 6975);
DISPLAY INVISIBLE (-450 6975);
FORCEADD UNIVERSAL_POWER..1
(-2525 4775);
FORCEPROP 3 LASTPIN (-2525 4725) SIG_NAME P3V3_AUX\g
J 0
(-2515 4735);
DISPLAY 0.659574 (-2515 4735);
PAINT MONO (-2515 4735);
DISPLAY INVISIBLE (-2515 4735);
FORCEPROP 1 LAST HDL_POWER P3V3_AUX
J 1
(-2525 4825);
DISPLAY 0.872340 (-2525 4825);
PAINT GREEN (-2525 4825);
FORCEPROP 2 LAST CDS_LIB pure_quanta_power
J 0
(-2525 4775);
DISPLAY INVISIBLE (-2525 4775);
FORCEPROP 1 LAST PATH I5
J 0
(-2475 4800);
DISPLAY 0.872340 (-2475 4800);
PAINT AQUA (-2475 4800);
DISPLAY INVISIBLE (-2475 4800);
FORCEADD Q_RES..1
(-525 8725);
FORCEPROP 1 LAST LOCATION R3807
J 0
(-725 8725);
DISPLAY 0.638298 (-725 8725);
FORCEPROP 0 LAST $SEC 1
J 0
(-575 8825);
DISPLAY 0.680851 (-575 8825);
PAINT MONO (-575 8825);
DISPLAY INVISIBLE (-575 8825);
FORCEPROP 0 LAST CDS_SEC 1
J 0
(-575 8825);
DISPLAY 1.021277 (-575 8825);
DISPLAY INVISIBLE (-575 8825);
FORCEPROP 1 LASTPIN (-625 8725) $PN 1
J 0
(-613 8737);
DISPLAY 0.787234 (-613 8737);
PAINT MONO (-613 8737);
FORCEPROP 1 LASTPIN (-425 8725) $PN 2
J 0
(-463 8737);
DISPLAY 0.787234 (-463 8737);
PAINT MONO (-463 8737);
FORCEPROP 1 LAST PACK_TYPE 0402LF
J 0
(-300 8725);
DISPLAY 0.510638 (-300 8725);
FORCEPROP 1 LAST TOLERANCE 5%
J 0
(-375 8725);
DISPLAY 0.510638 (-375 8725);
FORCEPROP 1 LAST WATTAGE 1/16W
J 2
(-350 8650);
DISPLAY 0.510638 (-350 8650);
FORCEPROP 0 LAST ROOM NIC_P3V3_BOM1
J 0
(-725 8825);
DISPLAY 0.680851 (-725 8825);
PAINT RED (-725 8825);
FORCEPROP 1 LAST VALUE 0
J 2
(-400 8725);
DISPLAY 0.510638 (-400 8725);
FORCEPROP 1 LAST MATERIAL CHIP
J 0
(-600 8650);
DISPLAY 0.510638 (-600 8650);
FORCEPROP 2 LAST CDS_LIB pure_quanta
J 0
(-525 8725);
DISPLAY INVISIBLE (-525 8725);
FORCEPROP 1 LAST PATH I50
J 0
(-575 8875);
DISPLAY 0.978723 (-575 8875);
PAINT WHITE (-575 8875);
DISPLAY INVISIBLE (-575 8875);
FORCEPROP 1 LAST PART_NUMBER CS00002JB13
J 0
(-600 8675);
DISPLAY 0.510638 (-600 8675);
DISPLAY INVISIBLE (-600 8675);
FORCEADD Q_RES..2
(-25 8100);
FORCEPROP 1 LAST LOCATION PR3812
J 0
(25 8175);
DISPLAY 0.638298 (25 8175);
FORCEPROP 0 LAST $SEC 1
J 0
(25 8225);
DISPLAY 0.680851 (25 8225);
PAINT MONO (25 8225);
DISPLAY INVISIBLE (25 8225);
FORCEPROP 0 LAST CDS_SEC 1
J 0
(25 8225);
DISPLAY 1.021277 (25 8225);
DISPLAY INVISIBLE (25 8225);
FORCEPROP 1 LASTPIN (-25 8200) $PN 1
J 0
(-20 8162);
DISPLAY 0.787234 (-20 8162);
PAINT MONO (-20 8162);
FORCEPROP 1 LASTPIN (-25 8000) $PN 2
J 0
(-20 8010);
DISPLAY 0.787234 (-20 8010);
PAINT MONO (-20 8010);
FORCEPROP 0 LAST ROOM NIC_P3V3_BOM1
J 0
(25 8000);
DISPLAY 0.446809 (25 8000);
PAINT RED (25 8000);
FORCEPROP 1 LAST WATTAGE 1/16W
J 0
(25 8100);
DISPLAY 0.404255 (25 8100);
FORCEPROP 1 LAST MATERIAL CHIP
J 0
(25 8075);
DISPLAY 0.404255 (25 8075);
FORCEPROP 1 LAST VALUE 15K
J 0
(25 8150);
DISPLAY 0.404255 (25 8150);
FORCEPROP 1 LAST TOLERANCE 1%
J 0
(25 8125);
DISPLAY 0.404255 (25 8125);
FORCEPROP 1 LAST PACK_TYPE 0402LF
J 0
(25 8025);
DISPLAY 0.404255 (25 8025);
FORCEPROP 2 LAST CDS_LIB pure_quanta
J 0
(-25 8100);
DISPLAY INVISIBLE (-25 8100);
FORCEPROP 1 LAST PATH I51
J 0
(25 8275);
DISPLAY 0.978723 (25 8275);
PAINT WHITE (25 8275);
DISPLAY INVISIBLE (25 8275);
FORCEPROP 1 LAST PART_NUMBER CS31502FB05
J 0
(25 8050);
DISPLAY 0.404255 (25 8050);
DISPLAY INVISIBLE (25 8050);
FORCEADD GND..1
(-25 7850);
FORCEPROP 3 LASTPIN (-25 7900) SIG_NAME GND\g
J 0
(-15 7910);
DISPLAY 0.659574 (-15 7910);
PAINT MONO (-15 7910);
DISPLAY INVISIBLE (-15 7910);
FORCEPROP 2 LAST CDS_LIB pure_quanta_power
J 0
(-25 7850);
DISPLAY INVISIBLE (-25 7850);
FORCEPROP 1 LAST SIZE 1B
J 0
(50 7800);
DISPLAY 0.872340 (50 7800);
PAINT GREEN (50 7800);
DISPLAY INVISIBLE (50 7800);
FORCEPROP 1 LAST HDL_POWER GND
J 0
(-25 8000);
DISPLAY 0.872340 (-25 8000);
PAINT GREEN (-25 8000);
DISPLAY INVISIBLE (-25 8000);
FORCEPROP 1 LAST PATH I52
J 0
(50 7850);
DISPLAY 0.872340 (50 7850);
PAINT AQUA (50 7850);
DISPLAY INVISIBLE (50 7850);
FORCEADD Q_RES..2
(-25 8375);
FORCEPROP 1 LAST LOCATION PR3829
J 0
(25 8425);
DISPLAY 0.510638 (25 8425);
FORCEPROP 0 LAST $SEC 1
J 0
(25 8500);
DISPLAY 0.680851 (25 8500);
PAINT MONO (25 8500);
DISPLAY INVISIBLE (25 8500);
FORCEPROP 0 LAST CDS_SEC 1
J 0
(25 8500);
DISPLAY 1.021277 (25 8500);
DISPLAY INVISIBLE (25 8500);
FORCEPROP 1 LASTPIN (-25 8475) $PN 1
J 0
(-20 8437);
DISPLAY 0.787234 (-20 8437);
PAINT MONO (-20 8437);
FORCEPROP 1 LASTPIN (-25 8275) $PN 2
J 0
(-20 8285);
DISPLAY 0.787234 (-20 8285);
PAINT MONO (-20 8285);
FORCEPROP 1 LAST PACK_TYPE 0402LF
J 0
(25 8275);
DISPLAY 0.404255 (25 8275);
FORCEPROP 1 LAST WATTAGE 1/16W
J 0
(25 8350);
DISPLAY 0.404255 (25 8350);
FORCEPROP 1 LAST VALUE 7.15K
J 0
(25 8400);
DISPLAY 0.404255 (25 8400);
FORCEPROP 1 LAST MATERIAL CHIP
J 0
(25 8325);
DISPLAY 0.404255 (25 8325);
FORCEPROP 1 LAST TOLERANCE 1%
J 0
(25 8375);
DISPLAY 0.404255 (25 8375);
FORCEPROP 0 LAST ROOM NIC_P3V3_BOM1
J 0
(25 8475);
DISPLAY 0.446809 (25 8475);
PAINT RED (25 8475);
FORCEPROP 2 LAST CDS_LIB pure_quanta
J 0
(-25 8375);
DISPLAY INVISIBLE (-25 8375);
FORCEPROP 1 LAST PATH I53
J 0
(25 8550);
DISPLAY 0.978723 (25 8550);
PAINT WHITE (25 8550);
DISPLAY INVISIBLE (25 8550);
FORCEPROP 1 LAST PART_NUMBER CS27152FB03
J 0
(25 8300);
DISPLAY 0.404255 (25 8300);
DISPLAY INVISIBLE (25 8300);
FORCEADD GND..1
(-375 9075);
FORCEPROP 3 LASTPIN (-375 9125) SIG_NAME GND\g
J 0
(-365 9135);
DISPLAY 0.659574 (-365 9135);
PAINT MONO (-365 9135);
DISPLAY INVISIBLE (-365 9135);
FORCEPROP 2 LAST CDS_LIB pure_quanta_power
J 0
(-375 9075);
DISPLAY INVISIBLE (-375 9075);
FORCEPROP 1 LAST SIZE 1B
J 0
(-300 9025);
DISPLAY 0.872340 (-300 9025);
PAINT GREEN (-300 9025);
DISPLAY INVISIBLE (-300 9025);
FORCEPROP 1 LAST HDL_POWER GND
J 0
(-375 9225);
DISPLAY 0.872340 (-375 9225);
PAINT GREEN (-375 9225);
DISPLAY INVISIBLE (-375 9225);
FORCEPROP 1 LAST PATH I54
J 0
(-300 9075);
DISPLAY 0.872340 (-300 9075);
PAINT AQUA (-300 9075);
DISPLAY INVISIBLE (-300 9075);
FORCEADD Q_CAP..1
(-375 9350);
FORCEPROP 1 LAST LOCATION PC2140
J 0
(-325 9425);
DISPLAY 0.638298 (-325 9425);
FORCEPROP 0 LAST $SEC 1
J 0
(-320 9492);
DISPLAY INVISIBLE (-320 9492);
FORCEPROP 0 LAST CDS_SEC 1
J 0
(-320 9492);
DISPLAY INVISIBLE (-320 9492);
FORCEPROP 1 LASTPIN (-375 9450) $PN 1
J 0
(-365 9430);
DISPLAY 0.787234 (-365 9430);
PAINT MONO (-365 9430);
DISPLAY INVISIBLE (-365 9430);
FORCEPROP 1 LASTPIN (-375 9250) $PN 2
J 0
(-365 9230);
DISPLAY 0.787234 (-365 9230);
PAINT MONO (-365 9230);
DISPLAY INVISIBLE (-365 9230);
FORCEPROP 1 LAST MATERIAL X6S
J 0
(-325 9350);
DISPLAY 0.510638 (-325 9350);
FORCEPROP 1 LAST VALUE 1UF
J 0
(-325 9400);
DISPLAY 0.510638 (-325 9400);
FORCEPROP 1 LAST VOLTAGE 25V
J 0
(-325 9375);
DISPLAY 0.510638 (-325 9375);
FORCEPROP 1 LAST PACK_TYPE C0402
J 0
(-325 9325);
DISPLAY 0.510638 (-325 9325);
FORCEPROP 2 LAST CDS_LIB pure_quanta
J 0
(-375 9350);
DISPLAY INVISIBLE (-375 9350);
FORCEPROP 1 LAST TOLERANCE 10%
J 0
(-325 9300);
DISPLAY 0.638298 (-325 9300);
DISPLAY INVISIBLE (-325 9300);
FORCEPROP 1 LAST PATH I55
J 0
(-325 9500);
DISPLAY 0.978723 (-325 9500);
PAINT WHITE (-325 9500);
DISPLAY INVISIBLE (-325 9500);
FORCEPROP 1 LAST PART_NUMBER CH5104KEB02
J 0
(-325 9300);
DISPLAY 0.510638 (-325 9300);
DISPLAY INVISIBLE (-325 9300);
FORCEADD Q_RES..2
(-25 9100);
FORCEPROP 1 LAST LOCATION PR3795
J 0
(25 9175);
DISPLAY 0.638298 (25 9175);
FORCEPROP 0 LAST $SEC 1
J 0
(25 9225);
DISPLAY 0.680851 (25 9225);
PAINT MONO (25 9225);
DISPLAY INVISIBLE (25 9225);
FORCEPROP 0 LAST CDS_SEC 1
J 0
(25 9225);
DISPLAY 1.021277 (25 9225);
DISPLAY INVISIBLE (25 9225);
FORCEPROP 1 LASTPIN (-25 9200) $PN 1
J 0
(-20 9162);
DISPLAY 0.787234 (-20 9162);
PAINT MONO (-20 9162);
FORCEPROP 1 LASTPIN (-25 9000) $PN 2
J 0
(-20 9010);
DISPLAY 0.787234 (-20 9010);
PAINT MONO (-20 9010);
FORCEPROP 0 LAST ROOM NIC_P3V3_BOM1
J 0
(25 9225);
DISPLAY 0.361702 (25 9225);
PAINT RED (25 9225);
FORCEPROP 1 LAST TOLERANCE 1%
J 0
(25 9125);
DISPLAY 0.404255 (25 9125);
FORCEPROP 1 LAST VALUE 25.5K
J 0
(25 9150);
DISPLAY 0.404255 (25 9150);
FORCEPROP 1 LAST PACK_TYPE 0402LF
J 0
(25 9025);
DISPLAY 0.404255 (25 9025);
FORCEPROP 1 LAST WATTAGE 1/16W
J 0
(25 9100);
DISPLAY 0.404255 (25 9100);
FORCEPROP 1 LAST MATERIAL CHIP
J 0
(25 9075);
DISPLAY 0.404255 (25 9075);
FORCEPROP 2 LAST CDS_LIB pure_quanta
J 0
(-25 9100);
DISPLAY INVISIBLE (-25 9100);
FORCEPROP 1 LAST PATH I56
J 0
(25 9275);
DISPLAY 0.978723 (25 9275);
PAINT WHITE (25 9275);
DISPLAY INVISIBLE (25 9275);
FORCEPROP 1 LAST PART_NUMBER CS32552FB06
J 0
(25 9050);
DISPLAY 0.404255 (25 9050);
DISPLAY INVISIBLE (25 9050);
FORCEADD UNIVERSAL_POWER..1
(-375 9700);
FORCEPROP 3 LASTPIN (-375 9650) SIG_NAME P3V3_AUX\g
J 0
(-365 9660);
DISPLAY 0.659574 (-365 9660);
PAINT MONO (-365 9660);
DISPLAY INVISIBLE (-365 9660);
FORCEPROP 1 LAST HDL_POWER P3V3_AUX
J 1
(-375 9750);
DISPLAY 0.872340 (-375 9750);
PAINT GREEN (-375 9750);
FORCEPROP 2 LAST CDS_LIB pure_quanta_power
J 0
(-375 9700);
DISPLAY INVISIBLE (-375 9700);
FORCEPROP 1 LAST PATH I57
J 0
(-325 9725);
DISPLAY 0.872340 (-325 9725);
PAINT AQUA (-325 9725);
DISPLAY INVISIBLE (-325 9725);
FORCEADD Q_RES..1
(425 4525);
FORCEPROP 1 LAST LOCATION R3142
J 0
(225 4525);
DISPLAY 0.638298 (225 4525);
FORCEPROP 2 LAST $SEC 1
J 0
(375 4725);
DISPLAY 0.680851 (375 4725);
PAINT MONO (375 4725);
DISPLAY INVISIBLE (375 4725);
FORCEPROP 2 LAST CDS_SEC 1
J 0
(375 4725);
DISPLAY 1.021277 (375 4725);
DISPLAY INVISIBLE (375 4725);
FORCEPROP 1 LASTPIN (325 4525) $PN 1
J 0
(337 4537);
DISPLAY 0.787234 (337 4537);
FORCEPROP 1 LASTPIN (525 4525) $PN 2
J 0
(487 4537);
DISPLAY 0.787234 (487 4537);
FORCEPROP 1 LAST TOLERANCE 5%
J 0
(600 4525);
DISPLAY 0.404255 (600 4525);
FORCEPROP 1 LAST VALUE 0
J 2
(575 4525);
DISPLAY 0.404255 (575 4525);
FORCEPROP 1 LAST MATERIAL CHIP
J 0
(350 4450);
DISPLAY 0.404255 (350 4450);
FORCEPROP 1 LAST WATTAGE 1/16W
J 2
(550 4450);
DISPLAY 0.404255 (550 4450);
FORCEPROP 1 LAST PACK_TYPE 0402LF
J 0
(650 4525);
DISPLAY 0.404255 (650 4525);
FORCEPROP 2 LAST CDS_LIB pure_quanta
J 0
(425 4525);
PAINT MONO (425 4525);
DISPLAY INVISIBLE (425 4525);
FORCEPROP 1 LAST PATH I59
J 0
(375 4675);
DISPLAY 0.978723 (375 4675);
PAINT WHITE (375 4675);
DISPLAY INVISIBLE (375 4675);
FORCEPROP 1 LAST PART_NUMBER CS00002JB13
J 0
(350 4475);
DISPLAY 0.404255 (350 4475);
DISPLAY INVISIBLE (350 4475);
FORCEADD Q_RES..2
(-2300 4475);
FORCEPROP 1 LAST LOCATION R3136
J 0
(-2255 4600);
DISPLAY 0.978723 (-2255 4600);
FORCEPROP 0 LAST $SEC 1
J 0
(-2250 4650);
DISPLAY 0.680851 (-2250 4650);
PAINT MONO (-2250 4650);
DISPLAY INVISIBLE (-2250 4650);
FORCEPROP 0 LAST CDS_SEC 1
J 0
(-2250 4650);
DISPLAY 1.021277 (-2250 4650);
DISPLAY INVISIBLE (-2250 4650);
FORCEPROP 1 LASTPIN (-2300 4575) $PN 1
J 0
(-2295 4537);
DISPLAY 0.787234 (-2295 4537);
PAINT MONO (-2295 4537);
FORCEPROP 1 LASTPIN (-2300 4375) $PN 2
J 0
(-2295 4385);
DISPLAY 0.787234 (-2295 4385);
PAINT MONO (-2295 4385);
FORCEPROP 1 LAST PACK_TYPE 0402LF
J 0
(-2260 4350);
DISPLAY 0.638298 (-2260 4350);
FORCEPROP 1 LAST MATERIAL CHIP
J 0
(-2260 4400);
DISPLAY 0.638298 (-2260 4400);
FORCEPROP 1 LAST VALUE 1K
J 0
(-2255 4550);
DISPLAY 0.638298 (-2255 4550);
FORCEPROP 1 LAST TOLERANCE 1%
J 0
(-2255 4500);
DISPLAY 0.638298 (-2255 4500);
FORCEPROP 1 LAST WATTAGE 1/16W
J 0
(-2260 4450);
DISPLAY 0.638298 (-2260 4450);
FORCEPROP 2 LAST CDS_LIB pure_quanta
J 0
(-2300 4475);
DISPLAY INVISIBLE (-2300 4475);
FORCEPROP 1 LAST PATH I6
J 0
(-2250 4650);
DISPLAY 0.978723 (-2250 4650);
PAINT WHITE (-2250 4650);
DISPLAY INVISIBLE (-2250 4650);
FORCEPROP 1 LAST PART_NUMBER CS21002FB06
J 0
(-2260 4350);
DISPLAY 0.638298 (-2260 4350);
DISPLAY INVISIBLE (-2260 4350);
FORCEADD OFFPAGE..2
(2050 4525);
FORCEPROP 2 LAST $XR0 80 
J 0
(2239 4525);
DISPLAY 0.638298 (2239 4525);
PAINT MONO (2239 4525);
FORCEPROP 2 LAST CDS_LIB standard
J 0
(2050 4525);
PAINT MONO (2050 4525);
DISPLAY INVISIBLE (2050 4525);
FORCEPROP 1 LAST OFFPAGE TRUE
J 0
(2375 4400);
DISPLAY 0.872340 (2375 4400);
DISPLAY INVISIBLE (2375 4400);
FORCEPROP 1 LAST COMMENT_BODY TRUE
J 0
(2005 4430);
DISPLAY 0.872340 (2005 4430);
PAINT GREEN (2005 4430);
DISPLAY INVISIBLE (2005 4430);
FORCEPROP 2 LAST PATH I61
J 0
(2250 4575);
DISPLAY 0.680851 (2250 4575);
DISPLAY INVISIBLE (2250 4575);
FORCEADD GND..1
(700 5500);
FORCEPROP 3 LASTPIN (700 5550) SIG_NAME GND\g
J 0
(710 5560);
DISPLAY 0.659574 (710 5560);
PAINT MONO (710 5560);
DISPLAY INVISIBLE (710 5560);
FORCEPROP 1 LAST SIZE 1B
J 0
(775 5450);
DISPLAY 0.872340 (775 5450);
PAINT GREEN (775 5450);
DISPLAY INVISIBLE (775 5450);
FORCEPROP 2 LAST CDS_LIB pure_quanta_power
J 0
(700 5500);
DISPLAY INVISIBLE (700 5500);
FORCEPROP 1 LAST HDL_POWER GND
J 0
(700 5650);
DISPLAY 0.872340 (700 5650);
PAINT GREEN (700 5650);
DISPLAY INVISIBLE (700 5650);
FORCEPROP 1 LAST PATH I62
J 0
(775 5500);
DISPLAY 0.872340 (775 5500);
PAINT AQUA (775 5500);
DISPLAY INVISIBLE (775 5500);
FORCEADD Q_RES..2
(700 5800);
FORCEPROP 1 LAST LOCATION PR3821
J 0
(750 5850);
DISPLAY 0.638298 (750 5850);
FORCEPROP 0 LAST $SEC 1
J 0
(750 5950);
DISPLAY 0.680851 (750 5950);
PAINT MONO (750 5950);
DISPLAY INVISIBLE (750 5950);
FORCEPROP 0 LAST CDS_SEC 1
J 0
(750 5925);
DISPLAY INVISIBLE (750 5925);
FORCEPROP 1 LASTPIN (700 5900) $PN 1
J 0
(705 5862);
DISPLAY 0.787234 (705 5862);
PAINT MONO (705 5862);
FORCEPROP 1 LASTPIN (700 5700) $PN 2
J 0
(705 5710);
DISPLAY 0.787234 (705 5710);
PAINT MONO (705 5710);
FORCEPROP 1 LAST PACK_TYPE 0402LF
J 0
(750 5700);
DISPLAY 0.510638 (750 5700);
FORCEPROP 1 LAST VALUE 30.1K
J 0
(750 5825);
DISPLAY 0.510638 (750 5825);
FORCEPROP 1 LAST WATTAGE 1/16W
J 0
(750 5775);
DISPLAY 0.510638 (750 5775);
FORCEPROP 1 LAST TOLERANCE 1%
J 0
(750 5800);
DISPLAY 0.510638 (750 5800);
FORCEPROP 1 LAST MATERIAL CHIP
J 0
(750 5750);
DISPLAY 0.510638 (750 5750);
FORCEPROP 0 LAST ROOM NIC_P12V_MAM_TIC_BOM1
J 0
(250 5725);
DISPLAY 0.446809 (250 5725);
PAINT RED (250 5725);
FORCEPROP 2 LAST CDS_LIB pure_quanta
J 0
(700 5800);
DISPLAY INVISIBLE (700 5800);
FORCEPROP 1 LAST PATH I63
J 0
(750 5975);
DISPLAY 0.978723 (750 5975);
PAINT WHITE (750 5975);
DISPLAY INVISIBLE (750 5975);
FORCEPROP 1 LAST PART_NUMBER CS33012FB03
J 0
(750 5725);
DISPLAY 0.510638 (750 5725);
DISPLAY INVISIBLE (750 5725);
FORCEADD GND..1
(175 6225);
FORCEPROP 3 LASTPIN (175 6275) SIG_NAME GND\g
J 0
(185 6285);
DISPLAY 0.659574 (185 6285);
PAINT MONO (185 6285);
DISPLAY INVISIBLE (185 6285);
FORCEPROP 2 LAST CDS_LIB pure_quanta_power
J 0
(175 6225);
DISPLAY INVISIBLE (175 6225);
FORCEPROP 1 LAST SIZE 1B
J 0
(250 6175);
DISPLAY 0.872340 (250 6175);
PAINT GREEN (250 6175);
DISPLAY INVISIBLE (250 6175);
FORCEPROP 1 LAST HDL_POWER GND
J 0
(175 6375);
DISPLAY 0.872340 (175 6375);
PAINT GREEN (175 6375);
DISPLAY INVISIBLE (175 6375);
FORCEPROP 1 LAST PATH I64
J 0
(250 6225);
DISPLAY 0.872340 (250 6225);
PAINT AQUA (250 6225);
DISPLAY INVISIBLE (250 6225);
FORCEADD Q_CAP..1
(175 6600);
FORCEPROP 1 LAST LOCATION PC2098
J 0
(225 6625);
DISPLAY 0.638298 (225 6625);
FORCEPROP 0 LAST $SEC 1
J 0
(225 6675);
DISPLAY 0.680851 (225 6675);
PAINT MONO (225 6675);
DISPLAY INVISIBLE (225 6675);
FORCEPROP 0 LAST CDS_SEC 1
J 0
(225 6675);
DISPLAY 1.021277 (225 6675);
DISPLAY INVISIBLE (225 6675);
FORCEPROP 1 LASTPIN (175 6700) $PN 1
J 0
(185 6680);
DISPLAY 0.787234 (185 6680);
PAINT MONO (185 6680);
FORCEPROP 1 LASTPIN (175 6500) $PN 2
J 0
(185 6480);
DISPLAY 0.787234 (185 6480);
PAINT MONO (185 6480);
FORCEPROP 1 LAST MATERIAL X6S
J 0
(225 6575);
DISPLAY 0.510638 (225 6575);
FORCEPROP 1 LAST VALUE 1UF
J 0
(225 6600);
DISPLAY 0.510638 (225 6600);
FORCEPROP 1 LAST VOLTAGE 25V
J 0
(225 6550);
DISPLAY 0.510638 (225 6550);
FORCEPROP 0 LAST ROOM NIC_P12V_MAM_TIC_BOM1
J 0
(125 6450);
DISPLAY 0.361702 (125 6450);
PAINT RED (125 6450);
FORCEPROP 1 LAST PACK_TYPE C0402
J 0
(225 6525);
DISPLAY 0.510638 (225 6525);
FORCEPROP 1 LAST TOLERANCE 10%
J 0
(225 6550);
DISPLAY 0.638298 (225 6550);
DISPLAY INVISIBLE (225 6550);
FORCEPROP 2 LAST CDS_LIB pure_quanta
J 0
(175 6600);
DISPLAY INVISIBLE (175 6600);
FORCEPROP 1 LAST PATH I65
J 0
(225 6750);
DISPLAY 0.978723 (225 6750);
PAINT WHITE (225 6750);
DISPLAY INVISIBLE (225 6750);
FORCEPROP 1 LAST PART_NUMBER CH5104KEB02
J 0
(225 6500);
DISPLAY 0.510638 (225 6500);
DISPLAY INVISIBLE (225 6500);
FORCEADD Q_CAP..1
R 1
(400 6300);
FORCEPROP 1 LAST LOCATION PC2146
J 0
(225 6350);
DISPLAY 0.638298 (225 6350);
FORCEPROP 0 LAST $SEC 1
R 1
J 0
(225 6400);
DISPLAY 0.680851 (225 6400);
PAINT MONO (225 6400);
DISPLAY INVISIBLE (225 6400);
FORCEPROP 0 LAST CDS_SEC 1
R 1
J 0
(225 6400);
DISPLAY 1.021277 (225 6400);
DISPLAY INVISIBLE (225 6400);
FORCEPROP 1 LASTPIN (300 6300) $PN 1
R 1
J 0
(320 6310);
DISPLAY 0.787234 (320 6310);
PAINT MONO (320 6310);
FORCEPROP 1 LASTPIN (500 6300) $PN 2
R 1
J 0
(520 6310);
DISPLAY 0.787234 (520 6310);
PAINT MONO (520 6310);
FORCEPROP 1 LAST VOLTAGE 25V
J 0
(550 6350);
DISPLAY 0.510638 (550 6350);
FORCEPROP 1 LAST VALUE 1UF
J 0
(375 6350);
DISPLAY 0.510638 (375 6350);
FORCEPROP 1 LAST PACK_TYPE C0402
J 0
(225 6250);
DISPLAY 0.510638 (225 6250);
FORCEPROP 0 LAST ROOM NIC_P12V_MAM_TIC_BOM1
J 0
(225 6225);
DISPLAY 0.361702 (225 6225);
PAINT RED (225 6225);
FORCEPROP 1 LAST TOLERANCE 10%
R 1
J 0
(450 6350);
DISPLAY 0.638298 (450 6350);
DISPLAY INVISIBLE (450 6350);
FORCEPROP 2 LAST CDS_LIB pure_quanta
J 0
(400 6300);
DISPLAY INVISIBLE (400 6300);
FORCEPROP 1 LAST MATERIAL X6S
R 1
J 0
(400 6350);
DISPLAY 0.638298 (400 6350);
DISPLAY INVISIBLE (400 6350);
FORCEPROP 1 LAST PATH I66
R 1
J 0
(250 6350);
DISPLAY 0.978723 (250 6350);
PAINT WHITE (250 6350);
DISPLAY INVISIBLE (250 6350);
FORCEPROP 1 LAST PART_NUMBER CH5104KEB02
J 0
(450 6250);
DISPLAY 0.510638 (450 6250);
DISPLAY INVISIBLE (450 6250);
FORCEADD MAX15090BEWIT..1
(1450 6300);
FORCEPROP 1 LAST LOCATION PU201
J 0
(1197 7028);
DISPLAY 0.723404 (1197 7028);
PAINT GREEN (1197 7028);
FORCEPROP 0 LAST $SEC 1
J 0
(1200 7175);
DISPLAY 0.680851 (1200 7175);
PAINT MONO (1200 7175);
DISPLAY INVISIBLE (1200 7175);
FORCEPROP 0 LAST CDS_SEC 1
J 0
(1200 7175);
DISPLAY 1.021277 (1200 7175);
DISPLAY INVISIBLE (1200 7175);
FORCEPROP 0 LASTPIN (1050 6000) $PN B1
J 2
(1040 6010);
DISPLAY 0.680851 (1040 6010);
PAINT MONO (1040 6010);
FORCEPROP 0 LASTPIN (1850 6000) $PN A7
J 0
(1860 6010);
DISPLAY 0.680851 (1860 6010);
PAINT MONO (1860 6010);
FORCEPROP 0 LASTPIN (1050 5900) $PN B7
J 2
(1040 5910);
DISPLAY 0.680851 (1040 5910);
PAINT MONO (1040 5910);
FORCEPROP 0 LASTPIN (1850 6200) $PN C7
J 0
(1860 6210);
DISPLAY 0.680851 (1860 6210);
PAINT MONO (1860 6210);
FORCEPROP 0 LASTPIN (1850 6400) $PN A6
J 0
(1860 6410);
DISPLAY 0.680851 (1860 6410);
PAINT MONO (1860 6410);
FORCEPROP 0 LASTPIN (1850 5900) $PN B2
J 0
(1860 5910);
DISPLAY 0.680851 (1860 5910);
PAINT MONO (1860 5910);
FORCEPROP 0 LASTPIN (1850 5850) $PN C1
J 0
(1860 5860);
DISPLAY 0.680851 (1860 5860);
PAINT MONO (1860 5860);
FORCEPROP 0 LASTPIN (1850 5800) $PN C2
J 0
(1860 5810);
DISPLAY 0.680851 (1860 5810);
PAINT MONO (1860 5810);
FORCEPROP 0 LASTPIN (1050 6800) $PN A3
J 2
(1040 6810);
DISPLAY 0.680851 (1040 6810);
PAINT MONO (1040 6810);
FORCEPROP 0 LASTPIN (1050 6750) $PN A5
J 2
(1040 6760);
DISPLAY 0.680851 (1040 6760);
PAINT MONO (1040 6760);
FORCEPROP 0 LASTPIN (1050 6700) $PN B3
J 2
(1040 6710);
DISPLAY 0.680851 (1040 6710);
PAINT MONO (1040 6710);
FORCEPROP 0 LASTPIN (1050 6650) $PN B5
J 2
(1040 6660);
DISPLAY 0.680851 (1040 6660);
PAINT MONO (1040 6660);
FORCEPROP 0 LASTPIN (1050 6600) $PN C3
J 2
(1040 6610);
DISPLAY 0.680851 (1040 6610);
PAINT MONO (1040 6610);
FORCEPROP 0 LASTPIN (1050 6550) $PN C5
J 2
(1040 6560);
DISPLAY 0.680851 (1040 6560);
PAINT MONO (1040 6560);
FORCEPROP 0 LASTPIN (1050 6500) $PN D5
J 2
(1040 6510);
DISPLAY 0.680851 (1040 6510);
PAINT MONO (1040 6510);
FORCEPROP 0 LASTPIN (1850 6100) $PN A1
J 0
(1860 6110);
DISPLAY 0.680851 (1860 6110);
PAINT MONO (1860 6110);
FORCEPROP 0 LASTPIN (1850 6800) $PN A4
J 0
(1860 6810);
DISPLAY 0.680851 (1860 6810);
PAINT MONO (1860 6810);
FORCEPROP 0 LASTPIN (1850 6750) $PN B4
J 0
(1860 6760);
DISPLAY 0.680851 (1860 6760);
PAINT MONO (1860 6760);
FORCEPROP 0 LASTPIN (1850 6700) $PN B6
J 0
(1860 6710);
DISPLAY 0.680851 (1860 6710);
PAINT MONO (1860 6710);
FORCEPROP 0 LASTPIN (1850 6650) $PN C4
J 0
(1860 6660);
DISPLAY 0.680851 (1860 6660);
PAINT MONO (1860 6660);
FORCEPROP 0 LASTPIN (1850 6600) $PN C6
J 0
(1860 6610);
DISPLAY 0.680851 (1860 6610);
PAINT MONO (1860 6610);
FORCEPROP 0 LASTPIN (1850 6550) $PN D4
J 0
(1860 6560);
DISPLAY 0.680851 (1860 6560);
PAINT MONO (1860 6560);
FORCEPROP 0 LASTPIN (1850 6500) $PN D6
J 0
(1860 6510);
DISPLAY 0.680851 (1860 6510);
PAINT MONO (1860 6510);
FORCEPROP 0 LASTPIN (1050 6100) $PN D3
J 2
(1040 6110);
DISPLAY 0.680851 (1040 6110);
PAINT MONO (1040 6110);
FORCEPROP 0 LASTPIN (1850 6300) $PN D7
J 0
(1860 6310);
DISPLAY 0.680851 (1860 6310);
PAINT MONO (1860 6310);
FORCEPROP 0 LASTPIN (1050 6300) $PN D1
J 2
(1040 6310);
DISPLAY 0.680851 (1040 6310);
PAINT MONO (1040 6310);
FORCEPROP 0 LASTPIN (1050 6200) $PN D2
J 2
(1040 6210);
DISPLAY 0.680851 (1040 6210);
PAINT MONO (1040 6210);
FORCEPROP 0 LASTPIN (1050 6400) $PN A2
J 2
(1040 6410);
DISPLAY 0.680851 (1040 6410);
PAINT MONO (1040 6410);
FORCEPROP 2 LAST VALUE MAX15090BEWI+T
J 0
(1200 7075);
DISPLAY 1.021277 (1200 7075);
FORCEPROP 2 LAST PART_TYPE SMLF
J 0
(1200 7125);
DISPLAY 1.021277 (1200 7125);
FORCEPROP 0 LAST ROOM NIC_P12V_MAM_TIC_BOM1
J 0
(1200 7225);
DISPLAY 0.680851 (1200 7225);
PAINT RED (1200 7225);
FORCEPROP 1 LAST MATERIAL IC
J 0
(1197 6855);
DISPLAY 0.723404 (1197 6855);
PAINT GREEN (1197 6855);
FORCEPROP 1 LAST CDS_LMAN_SYM_OUTLINE -250,550,250,-550
J 0
(1450 6300);
DISPLAY 0.468085 (1450 6300);
PAINT GREEN (1450 6300);
DISPLAY INVISIBLE (1450 6300);
FORCEPROP 1 LAST PIN_NAMES_ROTATE True
J 0
(1450 6300);
DISPLAY 0.489362 (1450 6300);
PAINT GREEN (1450 6300);
DISPLAY INVISIBLE (1450 6300);
FORCEPROP 2 LAST CDS_LIB pure_quanta
J 0
(1450 6300);
DISPLAY INVISIBLE (1450 6300);
FORCEPROP 1 LAST PATH I67
J 0
(1700 5750);
DISPLAY 0.723404 (1700 5750);
PAINT GREEN (1700 5750);
DISPLAY INVISIBLE (1700 5750);
FORCEPROP 1 LAST PART_NUMBER AL015080B00
J 0
(1197 6944);
DISPLAY 0.723404 (1197 6944);
PAINT GREEN (1197 6944);
DISPLAY INVISIBLE (1197 6944);
FORCEADD Q_RES..2
(1925 4950);
FORCEPROP 1 LAST LOCATION R3147
J 0
(1970 5075);
DISPLAY 0.978723 (1970 5075);
FORCEPROP 2 LAST $SEC 1
J 0
(1975 5175);
DISPLAY 0.680851 (1975 5175);
PAINT MONO (1975 5175);
DISPLAY INVISIBLE (1975 5175);
FORCEPROP 2 LAST CDS_SEC 1
J 0
(1975 5175);
DISPLAY 1.021277 (1975 5175);
DISPLAY INVISIBLE (1975 5175);
FORCEPROP 1 LASTPIN (1925 5050) $PN 1
J 0
(1930 5012);
DISPLAY 0.787234 (1930 5012);
FORCEPROP 1 LASTPIN (1925 4850) $PN 2
J 0
(1930 4860);
DISPLAY 0.787234 (1930 4860);
FORCEPROP 1 LAST VALUE 1K
J 0
(1970 5025);
DISPLAY 0.510638 (1970 5025);
FORCEPROP 1 LAST PACK_TYPE 0402LF
J 0
(1965 4825);
DISPLAY 0.510638 (1965 4825);
FORCEPROP 1 LAST TOLERANCE 1%
J 0
(1970 4975);
DISPLAY 0.510638 (1970 4975);
FORCEPROP 1 LAST WATTAGE 1/16W
J 0
(1965 4925);
DISPLAY 0.510638 (1965 4925);
FORCEPROP 1 LAST MATERIAL CHIP
J 0
(1965 4875);
DISPLAY 0.510638 (1965 4875);
FORCEPROP 2 LAST CDS_LIB pure_quanta
J 0
(1925 4950);
PAINT MONO (1925 4950);
DISPLAY INVISIBLE (1925 4950);
FORCEPROP 1 LAST PATH I69
J 0
(1975 5125);
DISPLAY 0.978723 (1975 5125);
PAINT WHITE (1975 5125);
DISPLAY INVISIBLE (1975 5125);
FORCEPROP 1 LAST PART_NUMBER CS21002FB06
J 0
(1965 4775);
DISPLAY 0.510638 (1965 4775);
DISPLAY INVISIBLE (1965 4775);
FORCEADD GND..1
(2175 5625);
FORCEPROP 3 LASTPIN (2175 5675) SIG_NAME GND\g
J 0
(2185 5685);
DISPLAY 0.659574 (2185 5685);
PAINT MONO (2185 5685);
DISPLAY INVISIBLE (2185 5685);
FORCEPROP 2 LAST CDS_LIB pure_quanta_power
J 0
(2175 5625);
DISPLAY INVISIBLE (2175 5625);
FORCEPROP 1 LAST SIZE 1B
J 0
(2250 5575);
DISPLAY 0.872340 (2250 5575);
PAINT GREEN (2250 5575);
DISPLAY INVISIBLE (2250 5575);
FORCEPROP 1 LAST HDL_POWER GND
J 0
(2175 5775);
DISPLAY 0.872340 (2175 5775);
PAINT GREEN (2175 5775);
DISPLAY INVISIBLE (2175 5775);
FORCEPROP 1 LAST PATH I70
J 0
(2250 5625);
DISPLAY 0.872340 (2250 5625);
PAINT AQUA (2250 5625);
DISPLAY INVISIBLE (2250 5625);
FORCEADD Q_RES..2
(2300 5925);
FORCEPROP 1 LAST LOCATION PR3823
J 0
(2345 6050);
DISPLAY 0.638298 (2345 6050);
FORCEPROP 0 LAST $SEC 1
J 0
(2350 6100);
DISPLAY 0.680851 (2350 6100);
PAINT MONO (2350 6100);
DISPLAY INVISIBLE (2350 6100);
FORCEPROP 0 LAST CDS_SEC 1
J 0
(2350 6100);
DISPLAY 1.021277 (2350 6100);
DISPLAY INVISIBLE (2350 6100);
FORCEPROP 1 LASTPIN (2300 6025) $PN 1
J 0
(2305 5987);
DISPLAY 0.787234 (2305 5987);
PAINT MONO (2305 5987);
FORCEPROP 1 LASTPIN (2300 5825) $PN 2
J 0
(2305 5835);
DISPLAY 0.787234 (2305 5835);
PAINT MONO (2305 5835);
FORCEPROP 1 LAST TOLERANCE 1%
J 0
(2345 5950);
DISPLAY 0.404255 (2345 5950);
FORCEPROP 1 LAST WATTAGE 1/16W
J 0
(2340 5900);
DISPLAY 0.404255 (2340 5900);
FORCEPROP 1 LAST MATERIAL CHIP
J 0
(2340 5850);
DISPLAY 0.404255 (2340 5850);
FORCEPROP 0 LAST ROOM NIC_P12V_MAM_TIC_BOM1
J 0
(2275 5725);
DISPLAY 0.361702 (2275 5725);
PAINT RED (2275 5725);
FORCEPROP 1 LAST PACK_TYPE 0402LF
J 0
(2340 5750);
DISPLAY 0.404255 (2340 5750);
FORCEPROP 1 LAST VALUE 845
J 0
(2345 6000);
DISPLAY 0.404255 (2345 6000);
FORCEPROP 2 LAST CDS_LIB pure_quanta
J 0
(2300 5925);
DISPLAY INVISIBLE (2300 5925);
FORCEPROP 1 LAST PATH I71
J 0
(2350 6100);
DISPLAY 0.978723 (2350 6100);
PAINT WHITE (2350 6100);
DISPLAY INVISIBLE (2350 6100);
FORCEPROP 1 LAST PART_NUMBER CS18452FB01
J 0
(2340 5800);
DISPLAY 0.404255 (2340 5800);
DISPLAY INVISIBLE (2340 5800);
FORCEADD Q_CAP..1
(2275 6625);
FORCEPROP 1 LAST LOCATION C40
J 0
(2325 6725);
DISPLAY 0.510638 (2325 6725);
FORCEPROP 0 LAST $SEC 1
J 0
(2325 6775);
DISPLAY 0.680851 (2325 6775);
PAINT MONO (2325 6775);
DISPLAY INVISIBLE (2325 6775);
FORCEPROP 0 LAST CDS_SEC 1
J 0
(2325 6775);
DISPLAY 1.021277 (2325 6775);
DISPLAY INVISIBLE (2325 6775);
FORCEPROP 1 LASTPIN (2275 6725) $PN 1
J 0
(2285 6705);
DISPLAY 0.787234 (2285 6705);
PAINT MONO (2285 6705);
FORCEPROP 1 LASTPIN (2275 6525) $PN 2
J 0
(2285 6505);
DISPLAY 0.787234 (2285 6505);
PAINT MONO (2285 6505);
FORCEPROP 1 LAST VALUE 0.01UF
J 0
(2325 6675);
DISPLAY 0.404255 (2325 6675);
FORCEPROP 1 LAST VOLTAGE 50V
J 0
(2330 6617);
DISPLAY 0.404255 (2330 6617);
FORCEPROP 1 LAST MATERIAL EMPTY
J 0
(2325 6475);
DISPLAY 0.638298 (2325 6475);
PAINT RED (2325 6475);
FORCEPROP 0 LAST ROOM NIC_P12V_MAM_TIC_BOM1
J 0
(2225 6450);
DISPLAY 0.361702 (2225 6450);
PAINT RED (2225 6450);
FORCEPROP 1 LAST PACK_TYPE C0402
J 0
(2330 6567);
DISPLAY 0.404255 (2330 6567);
FORCEPROP 1 LAST TOLERANCE 10%
J 0
(2325 6575);
DISPLAY 0.638298 (2325 6575);
DISPLAY INVISIBLE (2325 6575);
FORCEPROP 2 LAST CDS_LIB pure_quanta
J 0
(2275 6625);
DISPLAY INVISIBLE (2275 6625);
FORCEPROP 1 LAST PATH I72
J 0
(2325 6775);
DISPLAY 0.978723 (2325 6775);
PAINT WHITE (2325 6775);
DISPLAY INVISIBLE (2325 6775);
FORCEPROP 1 LAST PART_NUMBER CH31006KB18
J 0
(2330 6517);
DISPLAY 0.404255 (2330 6517);
DISPLAY INVISIBLE (2330 6517);
FORCEADD Q_RES..1
(3075 5975);
FORCEPROP 1 LAST LOCATION R3868
J 0
(3025 6000);
DISPLAY 0.638298 (3025 6000);
FORCEPROP 0 LAST $SEC 1
J 0
(3025 6075);
DISPLAY 0.680851 (3025 6075);
PAINT MONO (3025 6075);
DISPLAY INVISIBLE (3025 6075);
FORCEPROP 0 LAST CDS_SEC 1
J 0
(3025 6075);
DISPLAY 1.021277 (3025 6075);
DISPLAY INVISIBLE (3025 6075);
FORCEPROP 1 LASTPIN (2975 5975) $PN 1
J 0
(2987 5987);
DISPLAY 0.638298 (2987 5987);
PAINT MONO (2987 5987);
FORCEPROP 1 LASTPIN (3175 5975) $PN 2
J 0
(3137 5987);
DISPLAY 0.638298 (3137 5987);
PAINT MONO (3137 5987);
FORCEPROP 0 LAST ROOM NIC_P12V_MAM_TIC_BOM1
J 0
(2800 5875);
DISPLAY 0.553191 (2800 5875);
PAINT RED (2800 5875);
FORCEPROP 1 LAST WATTAGE 1/16W
J 2
(2875 5925);
DISPLAY 0.595745 (2875 5925);
FORCEPROP 1 LAST TOLERANCE 5%
J 0
(3250 5975);
DISPLAY 0.595745 (3250 5975);
FORCEPROP 1 LAST VALUE 0
J 2
(3225 5975);
DISPLAY 0.595745 (3225 5975);
FORCEPROP 1 LAST MATERIAL CHIP
J 0
(2850 5975);
DISPLAY 0.595745 (2850 5975);
FORCEPROP 1 LAST PACK_TYPE 0402LF
J 0
(3225 5925);
DISPLAY 0.595745 (3225 5925);
FORCEPROP 2 LAST CDS_LIB pure_quanta
J 0
(3075 5975);
DISPLAY INVISIBLE (3075 5975);
FORCEPROP 1 LAST PATH I73
J 0
(3025 6125);
DISPLAY 0.978723 (3025 6125);
PAINT WHITE (3025 6125);
DISPLAY INVISIBLE (3025 6125);
FORCEPROP 1 LAST PART_NUMBER CS00002JB13
J 0
(2900 5925);
DISPLAY 0.595745 (2900 5925);
DISPLAY INVISIBLE (2900 5925);
FORCEADD Q_RES..1
(3075 6100);
FORCEPROP 1 LAST LOCATION R3867
J 0
(3025 6150);
DISPLAY 0.978723 (3025 6150);
FORCEPROP 0 LAST $SEC 1
J 0
(3025 6200);
DISPLAY 0.680851 (3025 6200);
PAINT MONO (3025 6200);
DISPLAY INVISIBLE (3025 6200);
FORCEPROP 0 LAST CDS_SEC 1
J 0
(3025 6200);
DISPLAY 1.021277 (3025 6200);
DISPLAY INVISIBLE (3025 6200);
FORCEPROP 1 LASTPIN (2975 6100) $PN 1
J 0
(2987 6112);
DISPLAY 0.787234 (2987 6112);
PAINT MONO (2987 6112);
FORCEPROP 1 LASTPIN (3175 6100) $PN 2
J 0
(3137 6112);
DISPLAY 0.787234 (3137 6112);
PAINT MONO (3137 6112);
FORCEPROP 1 LAST MATERIAL EMPTY
J 0
(2850 6100);
DISPLAY 0.595745 (2850 6100);
PAINT RED (2850 6100);
FORCEPROP 1 LAST WATTAGE 1/16W
J 2
(2875 6050);
DISPLAY 0.595745 (2875 6050);
FORCEPROP 1 LAST VALUE 0
J 2
(3225 6100);
DISPLAY 0.595745 (3225 6100);
FORCEPROP 1 LAST TOLERANCE 5%
J 0
(3250 6100);
DISPLAY 0.595745 (3250 6100);
FORCEPROP 1 LAST PACK_TYPE 0402LF
J 0
(3225 6050);
DISPLAY 0.595745 (3225 6050);
FORCEPROP 2 LAST CDS_LIB pure_quanta
J 0
(3075 6100);
DISPLAY INVISIBLE (3075 6100);
FORCEPROP 1 LAST PATH I74
J 0
(3025 6250);
DISPLAY 0.978723 (3025 6250);
PAINT WHITE (3025 6250);
DISPLAY INVISIBLE (3025 6250);
FORCEPROP 1 LAST PART_NUMBER CS00002JB13
J 0
(2900 6050);
DISPLAY 0.595745 (2900 6050);
DISPLAY INVISIBLE (2900 6050);
FORCEADD Q_CAP..1
R 1
(2850 6400);
FORCEPROP 1 LAST LOCATION PC2150
J 0
(2575 6400);
DISPLAY 0.638298 (2575 6400);
FORCEPROP 0 LAST $SEC 1
R 1
J 0
(2950 6525);
DISPLAY 0.680851 (2950 6525);
PAINT MONO (2950 6525);
DISPLAY INVISIBLE (2950 6525);
FORCEPROP 0 LAST CDS_SEC 1
R 1
J 0
(2950 6525);
DISPLAY 1.021277 (2950 6525);
DISPLAY INVISIBLE (2950 6525);
FORCEPROP 1 LASTPIN (2750 6400) $PN 1
R 1
J 0
(2770 6410);
DISPLAY 0.787234 (2770 6410);
PAINT MONO (2770 6410);
FORCEPROP 1 LASTPIN (2950 6400) $PN 2
R 1
J 0
(2970 6410);
DISPLAY 0.787234 (2970 6410);
PAINT MONO (2970 6410);
FORCEPROP 1 LAST PACK_TYPE C0402
J 0
(2625 6350);
DISPLAY 0.638298 (2625 6350);
FORCEPROP 1 LAST VOLTAGE 50V
J 0
(2950 6475);
DISPLAY 0.638298 (2950 6475);
FORCEPROP 1 LAST VALUE 3900PF
J 0
(2750 6475);
DISPLAY 0.638298 (2750 6475);
FORCEPROP 0 LAST ROOM NIC_P12V_MAM_TIC_BOM1
J 0
(2725 6525);
DISPLAY 0.361702 (2725 6525);
PAINT RED (2725 6525);
FORCEPROP 2 LAST CDS_LIB pure_quanta
R 1
J 0
(2850 6400);
DISPLAY INVISIBLE (2850 6400);
FORCEPROP 1 LAST MATERIAL X7R
R 1
J 0
(2850 6450);
DISPLAY 0.638298 (2850 6450);
DISPLAY INVISIBLE (2850 6450);
FORCEPROP 1 LAST TOLERANCE 10%
R 1
J 0
(2900 6450);
DISPLAY 0.638298 (2900 6450);
DISPLAY INVISIBLE (2900 6450);
FORCEPROP 1 LAST PATH I75
R 1
J 0
(2700 6450);
DISPLAY 0.978723 (2700 6450);
PAINT WHITE (2700 6450);
DISPLAY INVISIBLE (2700 6450);
FORCEPROP 1 LAST PART_NUMBER CH23906KB14
J 0
(2900 6425);
DISPLAY 0.638298 (2900 6425);
DISPLAY INVISIBLE (2900 6425);
FORCEADD Q_RES..2
(2575 6625);
FORCEPROP 1 LAST LOCATION PR4522
J 0
(2625 6775);
DISPLAY 0.787234 (2625 6775);
FORCEPROP 0 LAST $SEC 1
J 0
(2625 6825);
DISPLAY 0.680851 (2625 6825);
PAINT MONO (2625 6825);
DISPLAY INVISIBLE (2625 6825);
FORCEPROP 0 LAST CDS_SEC 1
J 0
(2625 6825);
DISPLAY 1.021277 (2625 6825);
DISPLAY INVISIBLE (2625 6825);
FORCEPROP 1 LASTPIN (2575 6725) $PN 1
J 0
(2580 6687);
DISPLAY 0.787234 (2580 6687);
PAINT MONO (2580 6687);
FORCEPROP 1 LASTPIN (2575 6525) $PN 2
J 0
(2580 6535);
DISPLAY 0.787234 (2580 6535);
PAINT MONO (2580 6535);
FORCEPROP 1 LAST VALUE 10M
J 0
(2625 6750);
DISPLAY 0.404255 (2625 6750);
FORCEPROP 1 LAST WATTAGE 1/16W
J 0
(2625 6700);
DISPLAY 0.404255 (2625 6700);
FORCEPROP 1 LAST PACK_TYPE 0402LF
J 0
(2625 6625);
DISPLAY 0.404255 (2625 6625);
FORCEPROP 1 LAST MATERIAL CHIP
J 0
(2625 6675);
DISPLAY 0.404255 (2625 6675);
FORCEPROP 1 LAST TOLERANCE 1%
J 0
(2625 6725);
DISPLAY 0.404255 (2625 6725);
FORCEPROP 0 LAST ROOM NIC_P12V_MAM_TIC_BOM1
J 0
(2625 6600);
DISPLAY 0.446809 (2625 6600);
PAINT RED (2625 6600);
FORCEPROP 2 LAST CDS_LIB pure_quanta
J 0
(2575 6625);
DISPLAY INVISIBLE (2575 6625);
FORCEPROP 1 LAST PATH I76
J 0
(2625 6800);
DISPLAY 0.978723 (2625 6800);
PAINT WHITE (2625 6800);
DISPLAY INVISIBLE (2625 6800);
FORCEPROP 1 LAST PART_NUMBER CS61002FB02
J 0
(2625 6650);
DISPLAY 0.404255 (2625 6650);
DISPLAY INVISIBLE (2625 6650);
FORCEADD Q_RES..1
(2925 6300);
FORCEPROP 1 LAST LOCATION R3831
J 0
(2575 6300);
DISPLAY 0.638298 (2575 6300);
FORCEPROP 0 LAST $SEC 1
J 0
(2875 6375);
DISPLAY 0.680851 (2875 6375);
PAINT MONO (2875 6375);
DISPLAY INVISIBLE (2875 6375);
FORCEPROP 0 LAST CDS_SEC 1
J 0
(2875 6375);
DISPLAY 1.021277 (2875 6375);
DISPLAY INVISIBLE (2875 6375);
FORCEPROP 1 LASTPIN (2825 6300) $PN 1
J 0
(2837 6312);
DISPLAY 0.787234 (2837 6312);
PAINT MONO (2837 6312);
FORCEPROP 1 LASTPIN (3025 6300) $PN 2
J 0
(2987 6312);
DISPLAY 0.787234 (2987 6312);
PAINT MONO (2987 6312);
FORCEPROP 1 LAST MATERIAL CHIP
J 0
(2700 6300);
DISPLAY 0.595745 (2700 6300);
FORCEPROP 0 LAST ROOM NIC_P12V_MAM_TIC_BOM1
J 0
(2625 6225);
DISPLAY 0.446809 (2625 6225);
PAINT RED (2625 6225);
FORCEPROP 1 LAST PACK_TYPE 0402LF
J 0
(3075 6250);
DISPLAY 0.595745 (3075 6250);
FORCEPROP 1 LAST TOLERANCE 5%
J 0
(3100 6300);
DISPLAY 0.595745 (3100 6300);
FORCEPROP 1 LAST VALUE 0
J 2
(3075 6300);
DISPLAY 0.595745 (3075 6300);
FORCEPROP 1 LAST WATTAGE 1/16W
J 2
(2725 6250);
DISPLAY 0.595745 (2725 6250);
FORCEPROP 2 LAST CDS_LIB pure_quanta
J 0
(2925 6300);
DISPLAY INVISIBLE (2925 6300);
FORCEPROP 1 LAST PATH I77
J 0
(2875 6450);
DISPLAY 0.978723 (2875 6450);
PAINT WHITE (2875 6450);
DISPLAY INVISIBLE (2875 6450);
FORCEPROP 1 LAST PART_NUMBER CS00002JB13
J 0
(2750 6250);
DISPLAY 0.595745 (2750 6250);
DISPLAY INVISIBLE (2750 6250);
FORCEADD GND..1
(3025 6325);
FORCEPROP 3 LASTPIN (3025 6375) SIG_NAME GND\g
J 0
(3035 6385);
DISPLAY 0.659574 (3035 6385);
PAINT MONO (3035 6385);
DISPLAY INVISIBLE (3035 6385);
FORCEPROP 2 LAST CDS_LIB pure_quanta_power
J 0
(3025 6325);
DISPLAY INVISIBLE (3025 6325);
FORCEPROP 1 LAST SIZE 1B
J 0
(3100 6275);
DISPLAY 0.872340 (3100 6275);
PAINT GREEN (3100 6275);
DISPLAY INVISIBLE (3100 6275);
FORCEPROP 1 LAST HDL_POWER GND
J 0
(3025 6475);
DISPLAY 0.872340 (3025 6475);
PAINT GREEN (3025 6475);
DISPLAY INVISIBLE (3025 6475);
FORCEPROP 1 LAST PATH I78
J 0
(3100 6325);
DISPLAY 0.872340 (3100 6325);
PAINT AQUA (3100 6325);
DISPLAY INVISIBLE (3100 6325);
FORCEADD Q_RES..2
(3275 6550);
FORCEPROP 1 LAST LOCATION R3816
J 0
(3320 6675);
DISPLAY 0.638298 (3320 6675);
FORCEPROP 0 LAST $SEC 1
J 0
(3325 6725);
DISPLAY 0.680851 (3325 6725);
PAINT MONO (3325 6725);
DISPLAY INVISIBLE (3325 6725);
FORCEPROP 0 LAST CDS_SEC 1
J 0
(3325 6725);
DISPLAY 1.021277 (3325 6725);
DISPLAY INVISIBLE (3325 6725);
FORCEPROP 1 LASTPIN (3275 6650) $PN 1
J 0
(3280 6612);
DISPLAY 0.787234 (3280 6612);
PAINT MONO (3280 6612);
FORCEPROP 1 LASTPIN (3275 6450) $PN 2
J 0
(3280 6460);
DISPLAY 0.787234 (3280 6460);
PAINT MONO (3280 6460);
FORCEPROP 1 LAST VALUE 100K
J 0
(3320 6625);
DISPLAY 0.510638 (3320 6625);
FORCEPROP 1 LAST TOLERANCE 1%
J 0
(3320 6575);
DISPLAY 0.510638 (3320 6575);
FORCEPROP 0 LAST ROOM NIC_P12V_MAM_TIC_BOM1
J 0
(3325 6725);
DISPLAY 0.361702 (3325 6725);
PAINT RED (3325 6725);
FORCEPROP 1 LAST PACK_TYPE 0402LF
J 0
(3315 6375);
DISPLAY 0.510638 (3315 6375);
FORCEPROP 1 LAST MATERIAL CHIP
J 0
(3315 6475);
DISPLAY 0.510638 (3315 6475);
FORCEPROP 1 LAST WATTAGE 1/16W
J 0
(3315 6525);
DISPLAY 0.510638 (3315 6525);
FORCEPROP 2 LAST CDS_LIB pure_quanta
J 0
(3275 6550);
DISPLAY INVISIBLE (3275 6550);
FORCEPROP 1 LAST PATH I79
J 0
(3325 6725);
DISPLAY 0.978723 (3325 6725);
PAINT WHITE (3325 6725);
DISPLAY INVISIBLE (3325 6725);
FORCEPROP 1 LAST PART_NUMBER CS41002FB09
J 0
(3315 6425);
DISPLAY 0.510638 (3315 6425);
DISPLAY INVISIBLE (3315 6425);
FORCEADD GND..1
(-3075 5275);
FORCEPROP 3 LASTPIN (-3075 5325) SIG_NAME GND\g
J 0
(-3065 5335);
DISPLAY 0.659574 (-3065 5335);
PAINT MONO (-3065 5335);
DISPLAY INVISIBLE (-3065 5335);
FORCEPROP 2 LAST CDS_LIB pure_quanta_power
J 0
(-3075 5275);
DISPLAY INVISIBLE (-3075 5275);
FORCEPROP 1 LAST SIZE 1B
J 0
(-3000 5225);
DISPLAY 0.872340 (-3000 5225);
PAINT GREEN (-3000 5225);
DISPLAY INVISIBLE (-3000 5225);
FORCEPROP 1 LAST HDL_POWER GND
J 0
(-3075 5425);
DISPLAY 0.872340 (-3075 5425);
PAINT GREEN (-3075 5425);
DISPLAY INVISIBLE (-3075 5425);
FORCEPROP 1 LAST PATH I8
J 0
(-3000 5275);
DISPLAY 0.872340 (-3000 5275);
PAINT AQUA (-3000 5275);
DISPLAY INVISIBLE (-3000 5275);
FORCEADD Q_RES..2
(3700 6550);
FORCEPROP 1 LAST LOCATION R3825
J 0
(3745 6675);
DISPLAY 0.638298 (3745 6675);
FORCEPROP 0 LAST $SEC 1
J 0
(3750 6725);
DISPLAY 0.680851 (3750 6725);
PAINT MONO (3750 6725);
DISPLAY INVISIBLE (3750 6725);
FORCEPROP 0 LAST CDS_SEC 1
J 0
(3750 6725);
DISPLAY 1.021277 (3750 6725);
DISPLAY INVISIBLE (3750 6725);
FORCEPROP 1 LASTPIN (3700 6650) $PN 1
J 0
(3705 6612);
DISPLAY 0.787234 (3705 6612);
PAINT MONO (3705 6612);
FORCEPROP 1 LASTPIN (3700 6450) $PN 2
J 0
(3705 6460);
DISPLAY 0.787234 (3705 6460);
PAINT MONO (3705 6460);
FORCEPROP 1 LAST VALUE 100K
J 0
(3745 6625);
DISPLAY 0.510638 (3745 6625);
FORCEPROP 1 LAST MATERIAL CHIP
J 0
(3740 6475);
DISPLAY 0.510638 (3740 6475);
FORCEPROP 1 LAST TOLERANCE 1%
J 0
(3745 6575);
DISPLAY 0.510638 (3745 6575);
FORCEPROP 1 LAST WATTAGE 1/16W
J 0
(3740 6525);
DISPLAY 0.510638 (3740 6525);
FORCEPROP 1 LAST PACK_TYPE 0402LF
J 0
(3740 6375);
DISPLAY 0.510638 (3740 6375);
FORCEPROP 0 LAST ROOM NIC_P12V_MAM_TIC_BOM1
J 0
(3750 6725);
DISPLAY 0.446809 (3750 6725);
PAINT RED (3750 6725);
FORCEPROP 2 LAST CDS_LIB pure_quanta
J 0
(3700 6550);
DISPLAY INVISIBLE (3700 6550);
FORCEPROP 1 LAST PATH I80
J 0
(3750 6725);
DISPLAY 0.978723 (3750 6725);
PAINT WHITE (3750 6725);
DISPLAY INVISIBLE (3750 6725);
FORCEPROP 1 LAST PART_NUMBER CS41002FB09
J 0
(3740 6425);
DISPLAY 0.510638 (3740 6425);
DISPLAY INVISIBLE (3740 6425);
FORCEADD OFFPAGE..2
(4325 5975);
PAINT AQUA (4325 5975);
FORCEPROP 2 LAST $XR0 258 
J 0
(4514 5975);
DISPLAY 0.638298 (4514 5975);
PAINT MONO (4514 5975);
FORCEPROP 2 LAST CDS_LIB standard
J 0
(4325 5975);
DISPLAY INVISIBLE (4325 5975);
FORCEPROP 1 LAST OFFPAGE TRUE
J 0
(4650 5850);
DISPLAY 0.872340 (4650 5850);
PAINT AQUA (4650 5850);
DISPLAY INVISIBLE (4650 5850);
FORCEPROP 1 LAST COMMENT_BODY TRUE
J 0
(4280 5880);
DISPLAY 0.872340 (4280 5880);
PAINT GREEN (4280 5880);
DISPLAY INVISIBLE (4280 5880);
FORCEPROP 2 LAST PATH I81
J 0
(4525 6025);
DISPLAY 0.680851 (4525 6025);
DISPLAY INVISIBLE (4525 6025);
FORCEADD OFFPAGE..2
(4325 6100);
PAINT AQUA (4325 6100);
FORCEPROP 2 LAST $XR0 258 
J 0
(4514 6100);
DISPLAY 0.638298 (4514 6100);
PAINT MONO (4514 6100);
FORCEPROP 2 LAST CDS_LIB standard
J 0
(4325 6100);
DISPLAY INVISIBLE (4325 6100);
FORCEPROP 1 LAST OFFPAGE TRUE
J 0
(4650 5975);
DISPLAY 0.872340 (4650 5975);
PAINT AQUA (4650 5975);
DISPLAY INVISIBLE (4650 5975);
FORCEPROP 1 LAST COMMENT_BODY TRUE
J 0
(4280 6005);
DISPLAY 0.872340 (4280 6005);
PAINT GREEN (4280 6005);
DISPLAY INVISIBLE (4280 6005);
FORCEPROP 2 LAST PATH I82
J 0
(4525 6150);
DISPLAY 0.680851 (4525 6150);
DISPLAY INVISIBLE (4525 6150);
FORCEADD OFFPAGE..2
(4175 6300);
PAINT AQUA (4175 6300);
FORCEPROP 2 LAST $XR3 248 
J 0
(4364 6264);
DISPLAY 0.638298 (4364 6264);
PAINT MONO (4364 6264);
FORCEPROP 2 LAST $XR2 142 
J 0
(4604 6300);
DISPLAY 0.638298 (4604 6300);
PAINT MONO (4604 6300);
FORCEPROP 2 LAST $XR1 140 
J 0
(4484 6300);
DISPLAY 0.638298 (4484 6300);
PAINT MONO (4484 6300);
FORCEPROP 2 LAST $XR0 141 
J 0
(4364 6300);
DISPLAY 0.638298 (4364 6300);
PAINT MONO (4364 6300);
FORCEPROP 2 LAST CDS_LIB standard
J 0
(4175 6300);
DISPLAY INVISIBLE (4175 6300);
FORCEPROP 1 LAST OFFPAGE TRUE
J 0
(4500 6175);
DISPLAY 0.872340 (4500 6175);
PAINT AQUA (4500 6175);
DISPLAY INVISIBLE (4500 6175);
FORCEPROP 1 LAST COMMENT_BODY TRUE
J 0
(4130 6205);
DISPLAY 0.872340 (4130 6205);
PAINT GREEN (4130 6205);
DISPLAY INVISIBLE (4130 6205);
FORCEPROP 2 LAST PATH I83
J 0
(4500 6350);
DISPLAY 0.680851 (4500 6350);
DISPLAY INVISIBLE (4500 6350);
FORCEADD Q_RES..2
(175 7025);
FORCEPROP 1 LAST LOCATION PR3830
J 0
(225 7100);
DISPLAY 0.638298 (225 7100);
FORCEPROP 0 LAST $SEC 1
J 0
(225 7150);
DISPLAY 0.680851 (225 7150);
PAINT MONO (225 7150);
DISPLAY INVISIBLE (225 7150);
FORCEPROP 0 LAST CDS_SEC 1
J 0
(225 7150);
DISPLAY 1.021277 (225 7150);
DISPLAY INVISIBLE (225 7150);
FORCEPROP 1 LASTPIN (175 7125) $PN 1
J 0
(180 7087);
DISPLAY 0.787234 (180 7087);
PAINT MONO (180 7087);
FORCEPROP 1 LASTPIN (175 6925) $PN 2
J 0
(180 6935);
DISPLAY 0.787234 (180 6935);
PAINT MONO (180 6935);
FORCEPROP 1 LAST PACK_TYPE 0402LF
J 0
(225 6950);
DISPLAY 0.404255 (225 6950);
FORCEPROP 1 LAST MATERIAL CHIP
J 0
(225 7000);
DISPLAY 0.404255 (225 7000);
FORCEPROP 0 LAST ROOM NIC_P12V_MAM_TIC_BOM1
J 0
(225 7150);
DISPLAY 0.446809 (225 7150);
PAINT RED (225 7150);
FORCEPROP 1 LAST WATTAGE 1/16W
J 0
(225 7025);
DISPLAY 0.404255 (225 7025);
FORCEPROP 1 LAST TOLERANCE 1%
J 0
(225 7050);
DISPLAY 0.404255 (225 7050);
FORCEPROP 1 LAST VALUE 10
J 0
(225 7075);
DISPLAY 0.404255 (225 7075);
FORCEPROP 2 LAST CDS_LIB pure_quanta
J 0
(175 7025);
DISPLAY INVISIBLE (175 7025);
FORCEPROP 1 LAST PATH I84
J 0
(225 7200);
DISPLAY 0.978723 (225 7200);
PAINT WHITE (225 7200);
DISPLAY INVISIBLE (225 7200);
FORCEPROP 1 LAST PART_NUMBER CS01002FB07
J 0
(225 6975);
DISPLAY 0.404255 (225 6975);
DISPLAY INVISIBLE (225 6975);
FORCEADD GND..1
(300 8550);
FORCEPROP 3 LASTPIN (300 8600) SIG_NAME GND\g
J 0
(310 8610);
DISPLAY 0.659574 (310 8610);
PAINT MONO (310 8610);
DISPLAY INVISIBLE (310 8610);
FORCEPROP 1 LAST SIZE 1B
J 0
(375 8500);
DISPLAY 0.872340 (375 8500);
PAINT GREEN (375 8500);
DISPLAY INVISIBLE (375 8500);
FORCEPROP 2 LAST CDS_LIB pure_quanta_power
J 0
(300 8550);
DISPLAY INVISIBLE (300 8550);
FORCEPROP 1 LAST HDL_POWER GND
J 0
(300 8700);
DISPLAY 0.872340 (300 8700);
PAINT GREEN (300 8700);
DISPLAY INVISIBLE (300 8700);
FORCEPROP 1 LAST PATH I85
J 0
(375 8550);
DISPLAY 0.872340 (375 8550);
PAINT AQUA (375 8550);
DISPLAY INVISIBLE (375 8550);
FORCEADD Q_CAP..1
R 1
(525 8625);
FORCEPROP 1 LAST LOCATION PC2147
J 0
(350 8675);
DISPLAY 0.638298 (350 8675);
FORCEPROP 0 LAST $SEC 1
R 1
J 0
(350 8725);
DISPLAY 0.680851 (350 8725);
PAINT MONO (350 8725);
DISPLAY INVISIBLE (350 8725);
FORCEPROP 0 LAST CDS_SEC 1
R 1
J 0
(350 8725);
DISPLAY 1.021277 (350 8725);
DISPLAY INVISIBLE (350 8725);
FORCEPROP 1 LASTPIN (425 8625) $PN 1
R 1
J 0
(445 8635);
DISPLAY 0.787234 (445 8635);
PAINT MONO (445 8635);
FORCEPROP 1 LASTPIN (625 8625) $PN 2
R 1
J 0
(645 8635);
DISPLAY 0.787234 (645 8635);
PAINT MONO (645 8635);
FORCEPROP 1 LAST VALUE 1UF
J 0
(500 8675);
DISPLAY 0.510638 (500 8675);
FORCEPROP 1 LAST VOLTAGE 25V
J 0
(650 8675);
DISPLAY 0.510638 (650 8675);
FORCEPROP 0 LAST ROOM NIC_P3V3_BOM1
J 0
(350 8725);
DISPLAY 0.446809 (350 8725);
PAINT RED (350 8725);
FORCEPROP 1 LAST PACK_TYPE C0402
J 0
(350 8575);
DISPLAY 0.510638 (350 8575);
FORCEPROP 1 LAST MATERIAL X6S
R 1
J 0
(525 8675);
DISPLAY 0.638298 (525 8675);
DISPLAY INVISIBLE (525 8675);
FORCEPROP 2 LAST CDS_LIB pure_quanta
J 0
(525 8625);
DISPLAY INVISIBLE (525 8625);
FORCEPROP 1 LAST TOLERANCE 10%
R 1
J 0
(575 8675);
DISPLAY 0.638298 (575 8675);
DISPLAY INVISIBLE (575 8675);
FORCEPROP 1 LAST PATH I86
R 1
J 0
(375 8675);
DISPLAY 0.978723 (375 8675);
PAINT WHITE (375 8675);
DISPLAY INVISIBLE (375 8675);
FORCEPROP 1 LAST PART_NUMBER CH5104KEB02
J 0
(575 8575);
DISPLAY 0.510638 (575 8575);
DISPLAY INVISIBLE (575 8575);
FORCEADD GND..1
(825 7825);
FORCEPROP 3 LASTPIN (825 7875) SIG_NAME GND\g
J 0
(835 7885);
DISPLAY 0.659574 (835 7885);
PAINT MONO (835 7885);
DISPLAY INVISIBLE (835 7885);
FORCEPROP 1 LAST SIZE 1B
J 0
(900 7775);
DISPLAY 0.872340 (900 7775);
PAINT GREEN (900 7775);
DISPLAY INVISIBLE (900 7775);
FORCEPROP 2 LAST CDS_LIB pure_quanta_power
J 0
(825 7825);
DISPLAY INVISIBLE (825 7825);
FORCEPROP 1 LAST HDL_POWER GND
J 0
(825 7975);
DISPLAY 0.872340 (825 7975);
PAINT GREEN (825 7975);
DISPLAY INVISIBLE (825 7975);
FORCEPROP 1 LAST PATH I87
J 0
(900 7825);
DISPLAY 0.872340 (900 7825);
PAINT AQUA (900 7825);
DISPLAY INVISIBLE (900 7825);
FORCEADD Q_RES..2
(825 8125);
FORCEPROP 1 LAST LOCATION PR3822
J 0
(875 8175);
DISPLAY 0.638298 (875 8175);
FORCEPROP 0 LAST $SEC 1
J 0
(875 8275);
DISPLAY 0.680851 (875 8275);
PAINT MONO (875 8275);
DISPLAY INVISIBLE (875 8275);
FORCEPROP 0 LAST CDS_SEC 1
J 0
(875 8250);
DISPLAY INVISIBLE (875 8250);
FORCEPROP 1 LASTPIN (825 8225) $PN 1
J 0
(830 8187);
DISPLAY 0.787234 (830 8187);
PAINT MONO (830 8187);
FORCEPROP 1 LASTPIN (825 8025) $PN 2
J 0
(830 8035);
DISPLAY 0.787234 (830 8035);
PAINT MONO (830 8035);
FORCEPROP 1 LAST PACK_TYPE 0402LF
J 0
(875 8025);
DISPLAY 0.510638 (875 8025);
FORCEPROP 0 LAST ROOM NIC_P3V3_BOM1
J 0
(550 8050);
DISPLAY 0.446809 (550 8050);
PAINT RED (550 8050);
FORCEPROP 1 LAST TOLERANCE 1%
J 0
(875 8125);
DISPLAY 0.510638 (875 8125);
FORCEPROP 1 LAST VALUE 5.36K
J 0
(875 8150);
DISPLAY 0.510638 (875 8150);
FORCEPROP 1 LAST MATERIAL CHIP
J 0
(875 8075);
DISPLAY 0.510638 (875 8075);
FORCEPROP 1 LAST WATTAGE 1/16W
J 0
(875 8100);
DISPLAY 0.510638 (875 8100);
FORCEPROP 2 LAST CDS_LIB pure_quanta
J 0
(825 8125);
DISPLAY INVISIBLE (825 8125);
FORCEPROP 1 LAST PATH I88
J 0
(875 8300);
DISPLAY 0.978723 (875 8300);
PAINT WHITE (875 8300);
DISPLAY INVISIBLE (875 8300);
FORCEPROP 1 LAST PART_NUMBER CS25362FB02
J 0
(875 8050);
DISPLAY 0.510638 (875 8050);
DISPLAY INVISIBLE (875 8050);
FORCEADD MAX15090BEWIT..1
(1575 8625);
FORCEPROP 1 LAST LOCATION PU200
J 0
(1322 9353);
DISPLAY 0.723404 (1322 9353);
PAINT GREEN (1322 9353);
FORCEPROP 0 LAST $SEC 1
J 0
(1325 9500);
DISPLAY 0.680851 (1325 9500);
PAINT MONO (1325 9500);
DISPLAY INVISIBLE (1325 9500);
FORCEPROP 0 LAST CDS_SEC 1
J 0
(1325 9500);
DISPLAY 1.021277 (1325 9500);
DISPLAY INVISIBLE (1325 9500);
FORCEPROP 0 LASTPIN (1175 8325) $PN B1
J 2
(1165 8335);
DISPLAY 0.680851 (1165 8335);
PAINT MONO (1165 8335);
FORCEPROP 0 LASTPIN (1975 8325) $PN A7
J 0
(1985 8335);
DISPLAY 0.680851 (1985 8335);
PAINT MONO (1985 8335);
FORCEPROP 0 LASTPIN (1175 8225) $PN B7
J 2
(1165 8235);
DISPLAY 0.680851 (1165 8235);
PAINT MONO (1165 8235);
FORCEPROP 0 LASTPIN (1975 8525) $PN C7
J 0
(1985 8535);
DISPLAY 0.680851 (1985 8535);
PAINT MONO (1985 8535);
FORCEPROP 0 LASTPIN (1975 8725) $PN A6
J 0
(1985 8735);
DISPLAY 0.680851 (1985 8735);
PAINT MONO (1985 8735);
FORCEPROP 0 LASTPIN (1975 8225) $PN B2
J 0
(1985 8235);
DISPLAY 0.680851 (1985 8235);
PAINT MONO (1985 8235);
FORCEPROP 0 LASTPIN (1975 8175) $PN C1
J 0
(1985 8185);
DISPLAY 0.680851 (1985 8185);
PAINT MONO (1985 8185);
FORCEPROP 0 LASTPIN (1975 8125) $PN C2
J 0
(1985 8135);
DISPLAY 0.680851 (1985 8135);
PAINT MONO (1985 8135);
FORCEPROP 0 LASTPIN (1175 9125) $PN A3
J 2
(1165 9135);
DISPLAY 0.680851 (1165 9135);
PAINT MONO (1165 9135);
FORCEPROP 0 LASTPIN (1175 9075) $PN A5
J 2
(1165 9085);
DISPLAY 0.680851 (1165 9085);
PAINT MONO (1165 9085);
FORCEPROP 0 LASTPIN (1175 9025) $PN B3
J 2
(1165 9035);
DISPLAY 0.680851 (1165 9035);
PAINT MONO (1165 9035);
FORCEPROP 0 LASTPIN (1175 8975) $PN B5
J 2
(1165 8985);
DISPLAY 0.680851 (1165 8985);
PAINT MONO (1165 8985);
FORCEPROP 0 LASTPIN (1175 8925) $PN C3
J 2
(1165 8935);
DISPLAY 0.680851 (1165 8935);
PAINT MONO (1165 8935);
FORCEPROP 0 LASTPIN (1175 8875) $PN C5
J 2
(1165 8885);
DISPLAY 0.680851 (1165 8885);
PAINT MONO (1165 8885);
FORCEPROP 0 LASTPIN (1175 8825) $PN D5
J 2
(1165 8835);
DISPLAY 0.680851 (1165 8835);
PAINT MONO (1165 8835);
FORCEPROP 0 LASTPIN (1975 8425) $PN A1
J 0
(1985 8435);
DISPLAY 0.680851 (1985 8435);
PAINT MONO (1985 8435);
FORCEPROP 0 LASTPIN (1975 9125) $PN A4
J 0
(1985 9135);
DISPLAY 0.680851 (1985 9135);
PAINT MONO (1985 9135);
FORCEPROP 0 LASTPIN (1975 9075) $PN B4
J 0
(1985 9085);
DISPLAY 0.680851 (1985 9085);
PAINT MONO (1985 9085);
FORCEPROP 0 LASTPIN (1975 9025) $PN B6
J 0
(1985 9035);
DISPLAY 0.680851 (1985 9035);
PAINT MONO (1985 9035);
FORCEPROP 0 LASTPIN (1975 8975) $PN C4
J 0
(1985 8985);
DISPLAY 0.680851 (1985 8985);
PAINT MONO (1985 8985);
FORCEPROP 0 LASTPIN (1975 8925) $PN C6
J 0
(1985 8935);
DISPLAY 0.680851 (1985 8935);
PAINT MONO (1985 8935);
FORCEPROP 0 LASTPIN (1975 8875) $PN D4
J 0
(1985 8885);
DISPLAY 0.680851 (1985 8885);
PAINT MONO (1985 8885);
FORCEPROP 0 LASTPIN (1975 8825) $PN D6
J 0
(1985 8835);
DISPLAY 0.680851 (1985 8835);
PAINT MONO (1985 8835);
FORCEPROP 0 LASTPIN (1175 8425) $PN D3
J 2
(1165 8435);
DISPLAY 0.680851 (1165 8435);
PAINT MONO (1165 8435);
FORCEPROP 0 LASTPIN (1975 8625) $PN D7
J 0
(1985 8635);
DISPLAY 0.680851 (1985 8635);
PAINT MONO (1985 8635);
FORCEPROP 0 LASTPIN (1175 8625) $PN D1
J 2
(1165 8635);
DISPLAY 0.680851 (1165 8635);
PAINT MONO (1165 8635);
FORCEPROP 0 LASTPIN (1175 8525) $PN D2
J 2
(1165 8535);
DISPLAY 0.680851 (1165 8535);
PAINT MONO (1165 8535);
FORCEPROP 0 LASTPIN (1175 8725) $PN A2
J 2
(1165 8735);
DISPLAY 0.680851 (1165 8735);
PAINT MONO (1165 8735);
FORCEPROP 2 LAST PART_TYPE SMLF
J 0
(1325 9450);
DISPLAY 1.021277 (1325 9450);
FORCEPROP 0 LAST ROOM NIC_P3V3_BOM1
J 0
(1325 9550);
DISPLAY 0.680851 (1325 9550);
PAINT RED (1325 9550);
FORCEPROP 2 LAST VALUE MAX15090BEWI+T
J 0
(1325 9400);
DISPLAY 1.021277 (1325 9400);
FORCEPROP 1 LAST MATERIAL IC
J 0
(1322 9180);
DISPLAY 0.723404 (1322 9180);
PAINT GREEN (1322 9180);
FORCEPROP 2 LAST CDS_LIB pure_quanta
J 0
(1575 8625);
DISPLAY INVISIBLE (1575 8625);
FORCEPROP 1 LAST PIN_NAMES_ROTATE True
J 0
(1575 8625);
DISPLAY 0.489362 (1575 8625);
PAINT GREEN (1575 8625);
DISPLAY INVISIBLE (1575 8625);
FORCEPROP 1 LAST CDS_LMAN_SYM_OUTLINE -250,550,250,-550
J 0
(1575 8625);
DISPLAY 0.468085 (1575 8625);
PAINT GREEN (1575 8625);
DISPLAY INVISIBLE (1575 8625);
FORCEPROP 1 LAST PATH I89
J 0
(1825 8075);
DISPLAY 0.723404 (1825 8075);
PAINT GREEN (1825 8075);
DISPLAY INVISIBLE (1825 8075);
FORCEPROP 1 LAST PART_NUMBER AL015080B00
J 0
(1322 9269);
DISPLAY 0.723404 (1322 9269);
PAINT GREEN (1322 9269);
DISPLAY INVISIBLE (1322 9269);
FORCEADD Q_CAP..1
(300 8925);
FORCEPROP 1 LAST LOCATION C39
J 0
(350 8950);
DISPLAY 0.638298 (350 8950);
FORCEPROP 0 LAST $SEC 1
J 0
(350 9000);
DISPLAY 0.680851 (350 9000);
PAINT MONO (350 9000);
DISPLAY INVISIBLE (350 9000);
FORCEPROP 0 LAST CDS_SEC 1
J 0
(350 9000);
DISPLAY 1.021277 (350 9000);
DISPLAY INVISIBLE (350 9000);
FORCEPROP 1 LASTPIN (300 9025) $PN 1
J 0
(310 9005);
DISPLAY 0.787234 (310 9005);
PAINT MONO (310 9005);
FORCEPROP 1 LASTPIN (300 8825) $PN 2
J 0
(310 8805);
DISPLAY 0.787234 (310 8805);
PAINT MONO (310 8805);
FORCEPROP 0 LAST ROOM NIC_P3V3_BOM1
J 0
(350 9050);
DISPLAY 0.446809 (350 9050);
PAINT RED (350 9050);
FORCEPROP 1 LAST VALUE 1UF
J 0
(350 8925);
DISPLAY 0.510638 (350 8925);
FORCEPROP 1 LAST MATERIAL X6S
J 0
(350 8900);
DISPLAY 0.510638 (350 8900);
FORCEPROP 1 LAST VOLTAGE 25V
J 0
(350 8875);
DISPLAY 0.510638 (350 8875);
FORCEPROP 1 LAST PACK_TYPE C0402
J 0
(350 8850);
DISPLAY 0.510638 (350 8850);
FORCEPROP 1 LAST TOLERANCE 10%
J 0
(350 8875);
DISPLAY 0.638298 (350 8875);
DISPLAY INVISIBLE (350 8875);
FORCEPROP 2 LAST CDS_LIB pure_quanta
J 0
(300 8925);
DISPLAY INVISIBLE (300 8925);
FORCEPROP 1 LAST PATH I90
J 0
(350 9075);
DISPLAY 0.978723 (350 9075);
PAINT WHITE (350 9075);
DISPLAY INVISIBLE (350 9075);
FORCEPROP 1 LAST PART_NUMBER CH5104KEB02
J 0
(350 8825);
DISPLAY 0.510638 (350 8825);
DISPLAY INVISIBLE (350 8825);
FORCEADD Q_RES..2
(300 9350);
FORCEPROP 1 LAST LOCATION PR3782
J 0
(350 9425);
DISPLAY 0.638298 (350 9425);
FORCEPROP 0 LAST $SEC 1
J 0
(350 9475);
DISPLAY 0.680851 (350 9475);
PAINT MONO (350 9475);
DISPLAY INVISIBLE (350 9475);
FORCEPROP 0 LAST CDS_SEC 1
J 0
(350 9475);
DISPLAY 1.021277 (350 9475);
DISPLAY INVISIBLE (350 9475);
FORCEPROP 1 LASTPIN (300 9450) $PN 1
J 0
(305 9412);
DISPLAY 0.787234 (305 9412);
PAINT MONO (305 9412);
FORCEPROP 1 LASTPIN (300 9250) $PN 2
J 0
(305 9260);
DISPLAY 0.787234 (305 9260);
PAINT MONO (305 9260);
FORCEPROP 1 LAST WATTAGE 1/16W
J 0
(350 9350);
DISPLAY 0.404255 (350 9350);
FORCEPROP 1 LAST PACK_TYPE 0402LF
J 0
(350 9275);
DISPLAY 0.404255 (350 9275);
FORCEPROP 1 LAST MATERIAL CHIP
J 0
(350 9325);
DISPLAY 0.404255 (350 9325);
FORCEPROP 1 LAST TOLERANCE 1%
J 0
(350 9375);
DISPLAY 0.404255 (350 9375);
FORCEPROP 1 LAST VALUE 10
J 0
(350 9400);
DISPLAY 0.404255 (350 9400);
FORCEPROP 0 LAST ROOM NIC_P3V3_BOM1
J 0
(350 9475);
DISPLAY 0.553191 (350 9475);
PAINT RED (350 9475);
FORCEPROP 2 LAST CDS_LIB pure_quanta
J 0
(300 9350);
DISPLAY INVISIBLE (300 9350);
FORCEPROP 1 LAST PATH I91
J 0
(350 9525);
DISPLAY 0.978723 (350 9525);
PAINT WHITE (350 9525);
DISPLAY INVISIBLE (350 9525);
FORCEPROP 1 LAST PART_NUMBER CS01002FB07
J 0
(350 9300);
DISPLAY 0.404255 (350 9300);
DISPLAY INVISIBLE (350 9300);
FORCEADD SCHOTTKY_AC..1
R 1
(2675 7250);
FORCEPROP 1 LAST LOCATION PD108
J 0
(2725 7275);
DISPLAY 0.723404 (2725 7275);
PAINT GREEN (2725 7275);
FORCEPROP 0 LAST $SEC 1
R 1
J 0
(2725 7325);
DISPLAY INVISIBLE (2725 7325);
FORCEPROP 0 LAST CDS_SEC 1
R 1
J 0
(2725 7325);
DISPLAY INVISIBLE (2725 7325);
FORCEPROP 0 LASTPIN (2675 7125) $PN A
R 1
J 2
(2665 7160);
DISPLAY 0.808511 (2665 7160);
FORCEPROP 0 LASTPIN (2675 7375) $PN C
R 1
J 0
(2665 7335);
DISPLAY 0.808511 (2665 7335);
FORCEPROP 2 LAST VALUE B340A-13-F
J 0
(2725 7225);
DISPLAY 0.638298 (2725 7225);
FORCEPROP 1 LAST MATERIAL IC
J 0
(2725 7150);
DISPLAY 0.723404 (2725 7150);
PAINT GREEN (2725 7150);
FORCEPROP 0 LAST PART_TYPE SMLF
J 0
(2725 7425);
DISPLAY 1.021277 (2725 7425);
DISPLAY INVISIBLE (2725 7425);
FORCEPROP 1 LAST NEEDS_NO_SIZE TRUE
R 1
J 0
(2725 7325);
DISPLAY 0.468085 (2725 7325);
PAINT GREEN (2725 7325);
DISPLAY INVISIBLE (2725 7325);
FORCEPROP 2 LAST CDS_LIB pure_quanta
R 1
J 0
(2675 7250);
DISPLAY INVISIBLE (2675 7250);
FORCEPROP 1 LAST CDS_LMAN_SYM_OUTLINE -75,50,75,-50
R 1
J 0
(2675 7250);
DISPLAY 0.468085 (2675 7250);
PAINT GREEN (2675 7250);
DISPLAY INVISIBLE (2675 7250);
FORCEPROP 1 LAST PATH I92
R 1
J 0
(2675 7250);
DISPLAY 0.723404 (2675 7250);
PAINT GREEN (2675 7250);
DISPLAY INVISIBLE (2675 7250);
FORCEPROP 1 LAST PART_NUMBER BC000340Z30
J 0
(2725 7175);
DISPLAY 0.595745 (2725 7175);
PAINT GREEN (2725 7175);
DISPLAY INVISIBLE (2725 7175);
FORCEADD GND..1
(2300 7950);
FORCEPROP 3 LASTPIN (2300 8000) SIG_NAME GND\g
J 0
(2310 8010);
DISPLAY 0.659574 (2310 8010);
PAINT MONO (2310 8010);
DISPLAY INVISIBLE (2310 8010);
FORCEPROP 1 LAST SIZE 1B
J 0
(2375 7900);
DISPLAY 0.872340 (2375 7900);
PAINT GREEN (2375 7900);
DISPLAY INVISIBLE (2375 7900);
FORCEPROP 2 LAST CDS_LIB pure_quanta_power
J 0
(2300 7950);
DISPLAY INVISIBLE (2300 7950);
FORCEPROP 1 LAST HDL_POWER GND
J 0
(2300 8100);
DISPLAY 0.872340 (2300 8100);
PAINT GREEN (2300 8100);
DISPLAY INVISIBLE (2300 8100);
FORCEPROP 1 LAST PATH I93
J 0
(2375 7950);
DISPLAY 0.872340 (2375 7950);
PAINT AQUA (2375 7950);
DISPLAY INVISIBLE (2375 7950);
FORCEADD Q_RES..2
(2425 8275);
FORCEPROP 1 LAST LOCATION PR3824
J 0
(2470 8400);
DISPLAY 0.638298 (2470 8400);
FORCEPROP 0 LAST $SEC 1
J 0
(2475 8450);
DISPLAY 0.680851 (2475 8450);
PAINT MONO (2475 8450);
DISPLAY INVISIBLE (2475 8450);
FORCEPROP 0 LAST CDS_SEC 1
J 0
(2475 8450);
DISPLAY 1.021277 (2475 8450);
DISPLAY INVISIBLE (2475 8450);
FORCEPROP 1 LASTPIN (2425 8375) $PN 1
J 0
(2430 8337);
DISPLAY 0.787234 (2430 8337);
PAINT MONO (2430 8337);
FORCEPROP 1 LASTPIN (2425 8175) $PN 2
J 0
(2430 8185);
DISPLAY 0.787234 (2430 8185);
PAINT MONO (2430 8185);
FORCEPROP 1 LAST MATERIAL CHIP
J 0
(2465 8200);
DISPLAY 0.404255 (2465 8200);
FORCEPROP 1 LAST TOLERANCE 1%
J 0
(2470 8300);
DISPLAY 0.404255 (2470 8300);
FORCEPROP 1 LAST VALUE 4.53K
J 0
(2470 8350);
DISPLAY 0.404255 (2470 8350);
FORCEPROP 1 LAST WATTAGE 1/16W
J 0
(2465 8250);
DISPLAY 0.404255 (2465 8250);
FORCEPROP 1 LAST PACK_TYPE 0402LF
J 0
(2465 8100);
DISPLAY 0.404255 (2465 8100);
FORCEPROP 0 LAST ROOM NIC_P3V3_BOM1
J 0
(2450 8050);
DISPLAY 0.680851 (2450 8050);
PAINT RED (2450 8050);
FORCEPROP 2 LAST CDS_LIB pure_quanta
J 0
(2425 8275);
DISPLAY INVISIBLE (2425 8275);
FORCEPROP 1 LAST PATH I94
J 0
(2475 8450);
DISPLAY 0.978723 (2475 8450);
PAINT WHITE (2475 8450);
DISPLAY INVISIBLE (2475 8450);
FORCEPROP 1 LAST PART_NUMBER CS24532FB03
J 0
(2465 8150);
DISPLAY 0.404255 (2465 8150);
DISPLAY INVISIBLE (2465 8150);
FORCEADD Q_CAP..1
R 1
(3000 8725);
FORCEPROP 1 LAST LOCATION PC2151
J 0
(2725 8725);
DISPLAY 0.638298 (2725 8725);
FORCEPROP 0 LAST $SEC 1
R 1
J 0
(3100 8850);
DISPLAY 0.680851 (3100 8850);
PAINT MONO (3100 8850);
DISPLAY INVISIBLE (3100 8850);
FORCEPROP 0 LAST CDS_SEC 1
R 1
J 0
(3100 8850);
DISPLAY 1.021277 (3100 8850);
DISPLAY INVISIBLE (3100 8850);
FORCEPROP 1 LASTPIN (2900 8725) $PN 1
R 1
J 0
(2920 8735);
DISPLAY 0.787234 (2920 8735);
PAINT MONO (2920 8735);
FORCEPROP 1 LASTPIN (3100 8725) $PN 2
R 1
J 0
(3120 8735);
DISPLAY 0.787234 (3120 8735);
PAINT MONO (3120 8735);
FORCEPROP 1 LAST VOLTAGE 50V
J 0
(3100 8800);
DISPLAY 0.638298 (3100 8800);
FORCEPROP 1 LAST PACK_TYPE C0402
J 0
(2775 8675);
DISPLAY 0.638298 (2775 8675);
FORCEPROP 1 LAST VALUE 6800PF
J 0
(2900 8800);
DISPLAY 0.638298 (2900 8800);
FORCEPROP 0 LAST ROOM NIC_P3V3_BOM1
J 0
(2800 8850);
DISPLAY 0.680851 (2800 8850);
PAINT RED (2800 8850);
FORCEPROP 2 LAST CDS_LIB pure_quanta
R 1
J 0
(3000 8725);
DISPLAY INVISIBLE (3000 8725);
FORCEPROP 1 LAST MATERIAL X7R
R 1
J 0
(3000 8775);
DISPLAY 0.638298 (3000 8775);
DISPLAY INVISIBLE (3000 8775);
FORCEPROP 1 LAST TOLERANCE 10%
R 1
J 0
(3050 8775);
DISPLAY 0.638298 (3050 8775);
DISPLAY INVISIBLE (3050 8775);
FORCEPROP 1 LAST PATH I95
R 1
J 0
(2850 8775);
DISPLAY 0.978723 (2850 8775);
PAINT WHITE (2850 8775);
DISPLAY INVISIBLE (2850 8775);
FORCEPROP 1 LAST PART_NUMBER CH2686K1B01
J 0
(3050 8750);
DISPLAY 0.638298 (3050 8750);
DISPLAY INVISIBLE (3050 8750);
FORCEADD Q_CAP..1
(3150 7225);
FORCEPROP 1 LAST LOCATION PC2152
J 0
(3200 7325);
DISPLAY 0.638298 (3200 7325);
FORCEPROP 0 LAST $SEC 1
J 0
(3200 7375);
DISPLAY 0.680851 (3200 7375);
PAINT MONO (3200 7375);
DISPLAY INVISIBLE (3200 7375);
FORCEPROP 0 LAST CDS_SEC 1
J 0
(3200 7375);
DISPLAY 1.021277 (3200 7375);
DISPLAY INVISIBLE (3200 7375);
FORCEPROP 1 LASTPIN (3150 7325) $PN 1
J 0
(3160 7305);
DISPLAY 0.787234 (3160 7305);
PAINT MONO (3160 7305);
FORCEPROP 1 LASTPIN (3150 7125) $PN 2
J 0
(3160 7105);
DISPLAY 0.787234 (3160 7105);
PAINT MONO (3160 7105);
FORCEPROP 1 LAST PACK_TYPE 0402
J 0
(3200 7125);
DISPLAY 0.638298 (3200 7125);
FORCEPROP 1 LAST MATERIAL X7R
J 0
(3200 7175);
DISPLAY 0.638298 (3200 7175);
FORCEPROP 1 LAST VALUE 0.1UF
J 0
(3200 7275);
DISPLAY 0.638298 (3200 7275);
FORCEPROP 1 LAST VOLTAGE 25V
J 0
(3200 7225);
DISPLAY 0.638298 (3200 7225);
FORCEPROP 2 LAST CDS_LIB pure_quanta
J 0
(3150 7225);
DISPLAY INVISIBLE (3150 7225);
FORCEPROP 1 LAST TOLERANCE 10%
J 0
(3200 7175);
DISPLAY 0.978723 (3200 7175);
DISPLAY INVISIBLE (3200 7175);
FORCEPROP 1 LAST PATH I97
J 0
(3200 7375);
DISPLAY 0.978723 (3200 7375);
PAINT WHITE (3200 7375);
DISPLAY INVISIBLE (3200 7375);
FORCEPROP 1 LAST PART_NUMBER CH4104K1B00
J 0
(3200 7075);
DISPLAY 0.638298 (3200 7075);
DISPLAY INVISIBLE (3200 7075);
FORCEADD VCCAUX15..1
(3475 6900);
FORCEPROP 3 LASTPIN (3475 6850) SIG_NAME P3V3_AUX\g
J 0
(3485 6860);
DISPLAY 0.659574 (3485 6860);
PAINT MONO (3485 6860);
DISPLAY INVISIBLE (3485 6860);
FORCEPROP 1 LAST HDL_POWER P3V3_AUX
J 1
(3475 6950);
DISPLAY 0.723404 (3475 6950);
PAINT GREEN (3475 6950);
FORCEPROP 2 LAST CDS_LIB pure_quanta_power
J 0
(3475 6900);
DISPLAY INVISIBLE (3475 6900);
FORCEPROP 1 LAST PATH I98
J 0
(3525 6925);
DISPLAY 0.872340 (3525 6925);
PAINT AQUA (3525 6925);
DISPLAY INVISIBLE (3525 6925);
FORCEADD Q_CAP..1
(3575 7225);
FORCEPROP 1 LAST LOCATION PC2141
J 0
(3625 7325);
DISPLAY 0.638298 (3625 7325);
FORCEPROP 0 LAST $SEC 1
J 0
(3625 7375);
DISPLAY INVISIBLE (3625 7375);
FORCEPROP 0 LAST CDS_SEC 1
J 0
(3625 7375);
DISPLAY INVISIBLE (3625 7375);
FORCEPROP 1 LASTPIN (3575 7325) $PN 1
J 0
(3585 7305);
DISPLAY 0.787234 (3585 7305);
PAINT MONO (3585 7305);
DISPLAY INVISIBLE (3585 7305);
FORCEPROP 1 LASTPIN (3575 7125) $PN 2
J 0
(3585 7105);
DISPLAY 0.787234 (3585 7105);
PAINT MONO (3585 7105);
DISPLAY INVISIBLE (3585 7105);
FORCEPROP 1 LAST VALUE 22UF
J 0
(3625 7275);
DISPLAY 0.638298 (3625 7275);
FORCEPROP 1 LAST PACK_TYPE C0805
J 0
(3625 7125);
DISPLAY 0.638298 (3625 7125);
FORCEPROP 1 LAST VOLTAGE 16V
J 0
(3625 7225);
DISPLAY 0.638298 (3625 7225);
FORCEPROP 1 LAST MATERIAL X6S
J 0
(3625 7175);
DISPLAY 0.638298 (3625 7175);
FORCEPROP 1 LAST TOLERANCE 20%
J 0
(3625 7175);
DISPLAY 0.978723 (3625 7175);
DISPLAY INVISIBLE (3625 7175);
FORCEPROP 2 LAST CDS_LIB pure_quanta
J 0
(3575 7225);
DISPLAY INVISIBLE (3575 7225);
FORCEPROP 1 LAST PATH I99
J 0
(3625 7375);
DISPLAY 0.978723 (3625 7375);
PAINT WHITE (3625 7375);
DISPLAY INVISIBLE (3625 7375);
FORCEPROP 1 LAST PART_NUMBER CH6223MEA01
J 0
(3625 7075);
DISPLAY 0.638298 (3625 7075);
DISPLAY INVISIBLE (3625 7075);
FORCEADD DNS..2
(-3150 7875);
PAINT RED (-3150 7875);
FORCEPROP 2 LAST CDS_LIB mstr_misc
J 0
(-3150 7875);
DISPLAY INVISIBLE (-3150 7875);
FORCEPROP 1 LAST COMMENT_BODY TRUE
R 1
J 0
(-3075 7650);
DISPLAY 0.872340 (-3075 7650);
PAINT GREEN (-3075 7650);
DISPLAY INVISIBLE (-3075 7650);
FORCEADD DNS..2
(-3800 5800);
PAINT RED (-3800 5800);
FORCEPROP 2 LAST CDS_LIB mstr_misc
J 0
(-3800 5800);
DISPLAY INVISIBLE (-3800 5800);
FORCEPROP 1 LAST COMMENT_BODY TRUE
R 1
J 0
(-3725 5575);
DISPLAY 0.872340 (-3725 5575);
PAINT GREEN (-3725 5575);
DISPLAY INVISIBLE (-3725 5575);
FORCEADD DNS..2
(2425 8950);
PAINT RED (2425 8950);
FORCEPROP 2 LAST CDS_LIB mstr_misc
J 0
(2425 8950);
DISPLAY INVISIBLE (2425 8950);
FORCEPROP 1 LAST COMMENT_BODY TRUE
R 1
J 0
(2500 8725);
DISPLAY 0.872340 (2500 8725);
PAINT GREEN (2500 8725);
DISPLAY INVISIBLE (2500 8725);
FORCEADD DNS..2
(3050 8600);
PAINT RED (3050 8600);
FORCEPROP 2 LAST CDS_LIB mstr_misc
J 0
(3050 8600);
DISPLAY INVISIBLE (3050 8600);
FORCEPROP 1 LAST COMMENT_BODY TRUE
R 1
J 0
(3125 8375);
DISPLAY 0.872340 (3125 8375);
PAINT GREEN (3125 8375);
DISPLAY INVISIBLE (3125 8375);
FORCEADD DNS..2
(3100 6100);
PAINT RED (3100 6100);
FORCEPROP 2 LAST CDS_LIB mstr_misc
J 0
(3100 6100);
DISPLAY INVISIBLE (3100 6100);
FORCEPROP 1 LAST COMMENT_BODY TRUE
R 1
J 0
(3175 5875);
DISPLAY 0.872340 (3175 5875);
PAINT GREEN (3175 5875);
DISPLAY INVISIBLE (3175 5875);
FORCEADD CAD_NOTE..1
(2850 5750);
FORCEPROP 0 LAST S1 R3867/R3868 CO-LAYOUT
J 0
(2725 5625);
DISPLAY 0.808511 (2725 5625);
PAINT WHITE (2725 5625);
FORCEPROP 2 LAST CDS_LIB pure_quanta_power
J 0
(2850 5750);
DISPLAY INVISIBLE (2850 5750);
FORCEPROP 1 LAST COMMENT_BODY TRUE
J 0
(2875 5850);
DISPLAY 0.978723 (2875 5850);
DISPLAY INVISIBLE (2875 5850);
FORCEADD DNS..2
(-2800 7475);
PAINT RED (-2800 7475);
FORCEPROP 2 LAST CDS_LIB mstr_misc
J 0
(-2800 7475);
DISPLAY INVISIBLE (-2800 7475);
FORCEPROP 1 LAST COMMENT_BODY TRUE
R 1
J 0
(-2725 7250);
DISPLAY 0.872340 (-2725 7250);
PAINT GREEN (-2725 7250);
DISPLAY INVISIBLE (-2725 7250);
FORCEADD DNS..2
(4200 8875);
PAINT RED (4200 8875);
FORCEPROP 2 LAST CDS_LIB mstr_misc
J 0
(4200 8875);
DISPLAY INVISIBLE (4200 8875);
FORCEPROP 1 LAST COMMENT_BODY TRUE
R 1
J 0
(4275 8650);
DISPLAY 0.872340 (4275 8650);
PAINT GREEN (4275 8650);
DISPLAY INVISIBLE (4275 8650);
FORCEADD QUANTA_TITLE_BLOCK_C..1
(4725 3475);
FORCEPROP 0 LAST CDS_CON_LAST_MODIFIED Thu Sep 14 16:12:26 2023
J 0
(2840 3490);
DISPLAY INVISIBLE (2840 3490);
FORCEPROP 1 LAST CUSTOM_TXT_CDS <CON_LAST_MODIFIED>
J 0
(2840 3490);
DISPLAY 0.978723 (2840 3490);
FORCEPROP 2 LAST CUSTOM_TXT_CDS <XR_PAGE_TITLE>
J 0
(-3165 8725);
DISPLAY 0.638298 (-3165 8725);
PAINT PINK (-3165 8725);
DISPLAY INVISIBLE (-3165 8725);
FORCEPROP 1 LAST CUSTOM_TXT_CDS <NAME_2>
J 0
(1550 3525);
FORCEPROP 1 LAST CUSTOM_TXT_CDS <NAME_1>
J 0
(1550 3650);
FORCEPROP 1 LAST CUSTOM_TXT_CDS <Q_NUMBER>
J 0
(3322 3578);
DISPLAY 1.212766 (3322 3578);
FORCEPROP 1 LAST CUSTOM_TXT_CDS <Q_PROJ>
J 0
(2343 3577);
DISPLAY 1.212766 (2343 3577);
FORCEPROP 1 LAST CUSTOM_TXT_CDS <Q_REV>
J 0
(4541 3578);
DISPLAY 1.212766 (4541 3578);
FORCEPROP 1 LAST CUSTOM_TXT_CDS <CON_PAGE_NUM> OF <CON_TOTAL_PAGES>
J 0
(4279 3493);
DISPLAY 0.978723 (4279 3493);
FORCEPROP 1 LAST Q_TITLE V3_2_OCP3.0 HSC(1/3)
J 0
(-4641 3501);
DISPLAY 2.446809 (-4641 3501);
PAINT GREEN (-4641 3501);
FORCEPROP 2 LAST PAGE_BORDER TRUE
J 0
(-3165 8725);
DISPLAY 0.638298 (-3165 8725);
PAINT PINK (-3165 8725);
DISPLAY INVISIBLE (-3165 8725);
FORCEPROP 1 LAST CDS_LMAN_SYM_OUTLINE -9475,6775,100,-125
J 0
(4725 3475);
DISPLAY 0.468085 (4725 3475);
PAINT GREEN (4725 3475);
DISPLAY INVISIBLE (4725 3475);
FORCEPROP 2 LAST CDS_LIB pure_quanta
J 0
(4725 3475);
DISPLAY INVISIBLE (4725 3475);
FORCEPROP 2 LAST CDS_XR_PAGE_TITLE CR-140 : @T6G_MB_LIB.T6G(SCH_1):PAGE140
J 0
(-3165 8725);
DISPLAY 0.638298 (-3165 8725);
PAINT PINK (-3165 8725);
DISPLAY INVISIBLE (-3165 8725);
FORCEPROP 1 LAST Q_DEPT BU9
J 1
(962 3524);
DISPLAY 1.957447 (962 3524);
PAINT GREEN (962 3524);
DISPLAY INVISIBLE (962 3524);
FORCEPROP 1 LAST COMMENT_BODY TRUE
J 0
(4737 3462);
DISPLAY 0.978723 (4737 3462);
PAINT GREEN (4737 3462);
DISPLAY INVISIBLE (4737 3462);
FORCEADD DNS..2
(-3150 8275);
PAINT RED (-3150 8275);
FORCEPROP 2 LAST CDS_LIB mstr_misc
J 0
(-3150 8275);
DISPLAY INVISIBLE (-3150 8275);
FORCEPROP 1 LAST COMMENT_BODY TRUE
R 1
J 0
(-3075 8050);
DISPLAY 0.872340 (-3075 8050);
PAINT GREEN (-3075 8050);
DISPLAY INVISIBLE (-3075 8050);
FORCEADD DNS..2
(2300 6625);
PAINT RED (2300 6625);
FORCEPROP 2 LAST CDS_LIB mstr_misc
J 0
(2300 6625);
DISPLAY INVISIBLE (2300 6625);
FORCEPROP 1 LAST COMMENT_BODY TRUE
R 1
J 0
(2375 6400);
DISPLAY 0.872340 (2375 6400);
PAINT GREEN (2375 6400);
DISPLAY INVISIBLE (2375 6400);
FORCEADD DNS..2
(-3100 5525);
PAINT RED (-3100 5525);
FORCEPROP 2 LAST CDS_LIB mstr_misc
J 0
(-3100 5525);
DISPLAY INVISIBLE (-3100 5525);
FORCEPROP 1 LAST COMMENT_BODY TRUE
R 1
J 0
(-3025 5300);
DISPLAY 0.872340 (-3025 5300);
PAINT GREEN (-3025 5300);
DISPLAY INVISIBLE (-3025 5300);
WIRE 16 -1 (3100 8725)(3175 8725);
WIRE 16 -1 (3175 8725)(3175 8700);
WIRE 16 -1 (-2750 5675)(-2750 5600);
WIRE 16 -1 (-2750 6675)(-2750 6575);
WIRE 16 -1 (-1725 6000)(-1725 5950);
WIRE 16 -1 (-475 3850)(-475 3900);
WIRE 16 -1 (-475 4750)(-475 4800);
WIRE 16 -1 (-150 5675)(-150 5575);
WIRE 16 -1 (-2725 7400)(-2725 7325);
WIRE 16 -1 (-2225 7675)(-2225 7575);
WIRE 16 -1 (-2225 8675)(-2225 8575);
WIRE 16 -1 (-1525 8050)(-1525 7950);
WIRE 16 -1 (-25 8000)(-25 7900);
WIRE 16 -1 (-375 9250)(-375 9125);
WIRE 16 -1 (175 6500)(175 6300);
WIRE 16 -1 (175 6300)(300 6300);
WIRE 16 -1 (175 6300)(175 6275);
WIRE 16 -1 (2950 6400)(3025 6400);
WIRE 16 -1 (3025 6400)(3025 6375);
WIRE 16 -1 (-3075 5450)(-3075 5325);
WIRE 16 -1 (300 8825)(300 8625);
WIRE 16 -1 (300 8625)(425 8625);
WIRE 16 -1 (300 8625)(300 8600);
WIRE 16 -1 (-2075 5275)(-2075 5025);
WIRE 16 -1 (-1475 5025)(-2075 5025);
FORCEPROP 0 LAST CDS_PHYS_NET_NAME OCP_V3_2_PRSNT1_R_N
J 0
(-1585 5067);
PAINT MONO (-1585 5067);
DISPLAY INVISIBLE (-1585 5067);
WIRE 16 -1 (-2650 5025)(-2075 5025);
FORCEPROP 2 LAST SIG_NAME OCP_V3_2_PRSNT1_R_N
J 0
(-2085 5035);
DISPLAY 0.553191 (-2085 5035);
PAINT WHITE (-2085 5035);
WIRE 16 -1 (-2650 5125)(-2350 5125);
WIRE 16 -1 (-1475 5125)(-2350 5125);
FORCEPROP 0 LAST CDS_PHYS_NET_NAME OCP_V3_2_PRSNT0_R_N
J 0
(-1585 5167);
PAINT MONO (-1585 5167);
DISPLAY INVISIBLE (-1585 5167);
FORCEPROP 2 LAST SIG_NAME OCP_V3_2_PRSNT0_R_N
J 0
(-2085 5135);
DISPLAY 0.553191 (-2085 5135);
PAINT WHITE (-2085 5135);
WIRE 16 -1 (-2350 5275)(-2350 5125);
WIRE 16 -1 (-2075 5475)(-2075 5600);
WIRE 16 -1 (-2300 5600)(-2075 5600);
WIRE 16 -1 (-2300 5625)(-2300 5600);
WIRE 16 -1 (-2300 5600)(-2350 5600);
WIRE 16 -1 (-2350 5475)(-2350 5600);
WIRE 16 -1 (-2525 4575)(-2525 4700);
WIRE 16 -1 (-2300 4700)(-2525 4700);
WIRE 16 -1 (-2525 4725)(-2525 4700);
WIRE 16 -1 (-2300 4575)(-2300 4700);
WIRE 16 -1 (-1475 4225)(-2525 4225);
FORCEPROP 0 LAST CDS_PHYS_NET_NAME OCP_V3_2_PRSNT2_R_N
J 0
(-1585 4267);
PAINT MONO (-1585 4267);
DISPLAY INVISIBLE (-1585 4267);
FORCEPROP 2 LAST SIG_NAME OCP_V3_2_PRSNT2_R_N
J 0
(-2085 4235);
DISPLAY 0.553191 (-2085 4235);
PAINT WHITE (-2085 4235);
WIRE 16 -1 (-2525 4375)(-2525 4225);
WIRE 16 -1 (-2525 4225)(-2650 4225);
WIRE 16 2175 (-4280 9858)(-2577 9858);
WIRE 16 2175 (-4280 9858)(-4280 8958);
WIRE 16 2175 (-2577 9858)(-2577 8958);
WIRE 16 2175 (-4280 8958)(-2577 8958);
WIRE 16 -1 (-4075 7825)(-3275 7825);
FORCEPROP 2 LAST SIG_NAME P3V3_OCP_V3_2_EN_R
J 0
(-4035 7835);
DISPLAY 0.638298 (-4035 7835);
WIRE 16 -1 (-3275 8275)(-4150 8275);
FORCEPROP 2 LAST SIG_NAME HP_LVC3_OCP_V3_2_P12V_PWRGD
J 0
(-4135 8285);
DISPLAY 0.553191 (-4135 8285);
WIRE 16 -1 (-3200 8550)(-4150 8550);
FORCEPROP 2 LAST SIG_NAME P12V_OCP_V3_2_BUF_EN_R
J 0
(-4060 8560);
DISPLAY 0.680851 (-4060 8560);
WIRE 16 -1 (-3350 6350)(-4100 6350);
FORCEPROP 2 LAST SIG_NAME P12V_OCP_V3_2_BUF_EN_R
J 0
(-4060 6360);
DISPLAY 0.553191 (-4060 6360);
WIRE 16 -1 (3700 6800)(3475 6800);
WIRE 16 -1 (3700 6800)(3700 6650);
WIRE 16 -1 (3475 6850)(3475 6800);
WIRE 16 -1 (3475 6800)(3275 6800);
WIRE 16 -1 (3275 6800)(3275 6650);
WIRE 16 -1 (2050 8075)(2050 8125);
WIRE 16 -1 (2050 8075)(2100 8075);
WIRE 16 -1 (2050 8125)(1975 8125);
WIRE 16 -1 (2100 8075)(2150 8075);
WIRE 16 -1 (2100 8175)(2100 8075);
WIRE 16 -1 (1975 8175)(2100 8175);
WIRE 16 -1 (2150 8225)(2150 8075);
WIRE 16 -1 (2200 8075)(2150 8075);
WIRE 16 -1 (2200 8325)(2200 8075);
WIRE 16 -1 (2200 8075)(2300 8075);
WIRE 16 -1 (1975 8225)(2150 8225);
WIRE 16 -1 (2300 8075)(2425 8075);
WIRE 16 -1 (2300 8000)(2300 8075);
WIRE 16 -1 (1975 8325)(2200 8325);
WIRE 16 -1 (2425 8175)(2425 8075);
WIRE 16 -1 (1150 8225)(1150 7925);
WIRE 16 -1 (1175 8225)(1150 8225);
WIRE 16 -1 (1150 7925)(825 7925);
WIRE 16 -1 (825 7925)(825 8025);
WIRE 16 -1 (825 7875)(825 7925);
WIRE 16 -1 (1925 5750)(1925 5800);
WIRE 16 -1 (1925 5750)(1975 5750);
WIRE 16 -1 (1925 5800)(1850 5800);
WIRE 16 -1 (1975 5850)(1975 5750);
WIRE 16 -1 (1975 5750)(2025 5750);
WIRE 16 -1 (2075 5750)(2025 5750);
WIRE 16 -1 (2025 5900)(2025 5750);
WIRE 16 -1 (1850 5850)(1975 5850);
WIRE 16 -1 (1850 5900)(2025 5900);
WIRE 16 -1 (2075 6000)(2075 5750);
WIRE 16 -1 (2075 5750)(2175 5750);
WIRE 16 -1 (2175 5750)(2300 5750);
WIRE 16 -1 (2175 5675)(2175 5750);
WIRE 16 -1 (1850 6000)(2075 6000);
WIRE 16 -1 (2300 5825)(2300 5750);
WIRE 16 -1 (1025 5900)(1025 5600);
WIRE 16 -1 (1050 5900)(1025 5900);
WIRE 16 -1 (1025 5600)(700 5600);
WIRE 16 -1 (700 5600)(700 5700);
WIRE 16 -1 (700 5550)(700 5600);
WIRE 16 -1 (1075 8825)(1175 8825);
WIRE 16 -1 (1075 8875)(1075 8825);
WIRE 16 -1 (1075 8875)(1175 8875);
WIRE 16 -1 (1075 8925)(1075 8875);
WIRE 16 -1 (1075 8975)(1075 8925);
WIRE 16 -1 (1075 8925)(1175 8925);
WIRE 16 -1 (1075 8975)(1175 8975);
WIRE 16 -1 (1075 9025)(1075 8975);
WIRE 16 -1 (1075 9025)(1175 9025);
WIRE 16 -1 (1075 9075)(1075 9025);
WIRE 16 -1 (1075 9075)(1175 9075);
WIRE 16 -1 (1075 9125)(1075 9075);
WIRE 16 -1 (1075 9575)(1075 9125);
WIRE 16 -1 (1075 9125)(1175 9125);
WIRE 16 -1 (1075 9575)(300 9575);
WIRE 16 -1 (300 9575)(300 9450);
WIRE 16 -1 (-25 9575)(300 9575);
WIRE 16 -1 (-375 9575)(-25 9575);
WIRE 16 -1 (-25 9575)(-25 9200);
WIRE 16 -1 (-375 9650)(-375 9575);
WIRE 16 -1 (-375 9575)(-375 9450);
WIRE 16 -1 (950 6500)(1050 6500);
WIRE 16 -1 (950 6550)(950 6500);
WIRE 16 -1 (950 6550)(1050 6550);
WIRE 16 -1 (950 6600)(950 6550);
WIRE 16 -1 (950 6600)(1050 6600);
WIRE 16 -1 (950 6650)(950 6600);
WIRE 16 -1 (950 6650)(1050 6650);
WIRE 16 -1 (950 6700)(950 6650);
WIRE 16 -1 (950 6700)(1050 6700);
WIRE 16 -1 (950 6750)(950 6700);
WIRE 16 -1 (950 6750)(1050 6750);
WIRE 16 -1 (950 6800)(950 6750);
WIRE 16 -1 (950 6800)(1050 6800);
WIRE 16 -1 (950 7250)(950 6800);
WIRE 16 -1 (950 7250)(175 7250);
WIRE 16 -1 (175 7250)(175 7125);
WIRE 16 -1 (-150 7250)(175 7250);
WIRE 16 -1 (-500 7250)(-150 7250);
WIRE 16 -1 (-150 7250)(-150 6825);
WIRE 16 -1 (-500 7250)(-725 7250);
WIRE 16 -1 (-500 7250)(-500 7125);
WIRE 16 -1 (-725 7325)(-725 7250);
WIRE 16 -1 (-875 7250)(-725 7250);
WIRE 16 -1 (-875 7175)(-875 7250);
WIRE 16 -1 (-500 6760)(-500 6925);
WIRE 16 -1 (-500 6760)(-725 6760);
WIRE 16 -1 (-725 6700)(-725 6760);
WIRE 16 -1 (-875 6760)(-725 6760);
WIRE 16 -1 (-875 6875)(-875 6760);
WIRE 16 -1 (-475 5000)(-475 5075);
WIRE 16 -1 (-475 5125)(-475 5075);
WIRE 16 -1 (-475 5075)(-825 5075);
WIRE 16 -1 (-1550 5075)(-1475 5075);
WIRE 16 -1 (-1550 4850)(-1550 5075);
WIRE 16 -1 (-475 4100)(-475 4175);
WIRE 16 -1 (-475 4225)(-475 4175);
WIRE 16 -1 (-475 4175)(-825 4175);
WIRE 16 -1 (-1550 4175)(-1475 4175);
WIRE 16 -1 (-1550 3925)(-1550 4175);
WIRE 16 -1 (1750 5050)(1750 5125);
WIRE 16 -1 (1750 5125)(1925 5125);
WIRE 16 -1 (1925 5050)(1925 5125);
WIRE 16 -1 (1925 5125)(1925 5175);
WIRE 16 -1 (1975 8825)(2282 8825);
WIRE 16 -1 (2282 8825)(2282 8875);
WIRE 16 -1 (2282 8875)(2282 8925);
WIRE 16 -1 (1975 8875)(2282 8875);
WIRE 16 -1 (2282 8925)(2282 8975);
WIRE 16 -1 (2282 8925)(1975 8925);
WIRE 16 -1 (2282 8975)(2282 9025);
WIRE 16 -1 (1975 8975)(2282 8975);
WIRE 16 -1 (2282 9025)(2282 9075);
WIRE 16 -1 (1975 9025)(2282 9025);
WIRE 16 -1 (2282 9075)(2282 9125);
WIRE 16 -1 (1975 9075)(2282 9075);
WIRE 16 -1 (2282 9125)(2400 9125);
WIRE 16 -1 (1975 9125)(2282 9125);
WIRE 16 -1 (2400 9125)(2495 9125);
WIRE 16 -1 (2400 9050)(2400 9125);
WIRE 16 -1 (2495 9750)(2495 9125);
WIRE 16 -1 (2495 9125)(2675 9125);
WIRE 16 -1 (2675 9125)(2675 9075);
WIRE 16 -1 (2495 9750)(2800 9750);
WIRE 16 -1 (2800 9750)(3300 9750);
WIRE 16 -1 (2800 9750)(2800 9700);
WIRE 16 -1 (3875 9750)(3300 9750);
WIRE 16 -1 (3300 9650)(3300 9750);
WIRE 16 -1 (3875 9800)(3875 9750);
WIRE 16 -1 (3875 9650)(3875 9750);
WIRE 16 -1 (2800 9450)(2800 9375);
WIRE 16 -1 (2800 9375)(3300 9375);
WIRE 16 -1 (3875 9375)(3300 9375);
WIRE 16 -1 (3300 9375)(3300 9450);
WIRE 16 -1 (3875 9375)(3875 9450);
WIRE 16 -1 (3875 9300)(3875 9375);
WIRE 16 -1 (3425 9150)(3625 9150);
WIRE 16 -1 (3425 9150)(3425 9025);
WIRE 16 -1 (4100 9150)(3625 9150);
WIRE 16 -1 (3625 9200)(3625 9150);
WIRE 16 -1 (4100 9150)(4100 9025);
WIRE 16 -1 (1850 6500)(2157 6500);
WIRE 16 -1 (2157 6500)(2157 6550);
WIRE 16 -1 (2157 6550)(2157 6600);
WIRE 16 -1 (1850 6550)(2157 6550);
WIRE 16 -1 (2157 6600)(2157 6650);
WIRE 16 -1 (2157 6600)(1850 6600);
WIRE 16 -1 (2157 6650)(2157 6700);
WIRE 16 -1 (1850 6650)(2157 6650);
WIRE 16 -1 (2157 6700)(2157 6750);
WIRE 16 -1 (1850 6700)(2157 6700);
WIRE 16 -1 (2157 6750)(2157 6800);
WIRE 16 -1 (1850 6750)(2157 6750);
WIRE 16 -1 (2157 6800)(2275 6800);
WIRE 16 -1 (1850 6800)(2157 6800);
WIRE 16 -1 (2275 6800)(2370 6800);
WIRE 16 -1 (2275 6725)(2275 6800);
WIRE 16 -1 (2370 7425)(2370 6800);
WIRE 16 -1 (2370 6800)(2575 6800);
WIRE 16 -1 (2575 6800)(2575 6725);
WIRE 16 -1 (2370 7425)(2675 7425);
WIRE 16 -1 (3150 7425)(2675 7425);
WIRE 16 -1 (2675 7425)(2675 7375);
WIRE 16 -1 (3575 7425)(3150 7425);
WIRE 16 -1 (3150 7325)(3150 7425);
WIRE 16 -1 (3975 7425)(3575 7425);
WIRE 16 -1 (3575 7425)(3575 7325);
WIRE 16 -1 (3975 7475)(3975 7425);
WIRE 16 -1 (3975 7325)(3975 7425);
WIRE 16 -1 (2675 7125)(2675 7050);
WIRE 16 -1 (2675 7050)(3150 7050);
WIRE 16 -1 (3575 7050)(3150 7050);
WIRE 16 -1 (3150 7050)(3150 7125);
WIRE 16 -1 (3975 7050)(3575 7050);
WIRE 16 -1 (3575 7050)(3575 7125);
WIRE 16 -1 (3975 7050)(3975 7125);
WIRE 16 -1 (3975 6975)(3975 7050);
WIRE 16 -1 (-2725 7600)(-2725 7825);
WIRE 16 -1 (-2725 7825)(-2475 7825);
WIRE 16 -1 (-2950 7825)(-2725 7825);
FORCEPROP 2 LAST SIG_NAME P3V3_OCP_EN_2_R
J 0
(-2935 7835);
DISPLAY 0.595745 (-2935 7835);
FORCEPROP 2 LASTPROP $XRERR UNIQUE?
J 0
(-3175 7835);
DISPLAY 0.638298 (-3175 7835);
PAINT MONO (-3175 7835);
DISPLAY INVISIBLE (-3175 7835);
WIRE 16 -1 (-2950 8275)(-2950 7825);
WIRE 16 -1 (-3075 7825)(-2950 7825);
WIRE 16 -1 (-2950 8550)(-2950 8275);
WIRE 16 -1 (-3075 8275)(-2950 8275);
WIRE 16 -1 (-3000 8550)(-2950 8550);
WIRE 16 -1 (3025 6300)(3700 6300);
WIRE 16 -1 (3700 6300)(4125 6300);
WIRE 16 -1 (3700 6450)(3700 6300);
FORCEPROP 2 LAST SIG_NAME HP_LVC3_OCP_V3_2_P12V_PWRGD
J 0
(3415 6310);
DISPLAY 0.574468 (3415 6310);
WIRE 16 -1 (-2750 6375)(-2750 6150);
WIRE 16 -1 (-2750 6150)(-1975 6150);
FORCEPROP 2 LAST SIG_NAME P12V_OCP_2_EN_G
J 0
(-2710 6160);
DISPLAY 0.595745 (-2710 6160);
FORCEPROP 2 LASTPROP $XRERR UNIQUE?
J 0
(-2950 6160);
DISPLAY 0.638298 (-2950 6160);
PAINT MONO (-2950 6160);
DISPLAY INVISIBLE (-2950 6160);
WIRE 16 -1 (-2750 6075)(-2750 6150);
WIRE 16 -1 (-3150 6350)(-3100 6350);
WIRE 16 -1 (-3100 6350)(-3100 5825);
WIRE 16 -1 (-3100 5825)(-3075 5825);
WIRE 16 -1 (-3675 5825)(-3100 5825);
FORCEPROP 2 LAST SIG_NAME P12V_OCP_EN_2_R
J 0
(-3535 5825);
DISPLAY 0.595745 (-3535 5825);
FORCEPROP 2 LASTPROP $XRERR UNIQUE?
J 0
(-3775 5825);
DISPLAY 0.638298 (-3775 5825);
PAINT MONO (-3775 5825);
DISPLAY INVISIBLE (-3775 5825);
WIRE 16 -1 (-3075 5825)(-3000 5825);
WIRE 16 -1 (-3075 5650)(-3075 5825);
WIRE 16 -1 (-4300 5825)(-3875 5825);
FORCEPROP 2 LAST SIG_NAME P12V_OCP_V3_2_EN_R
J 0
(-4260 5835);
DISPLAY 0.446809 (-4260 5835);
PAINT WHITE (-4260 5835);
WIRE 16 -1 (-850 6400)(-1725 6400);
FORCEPROP 2 LAST SIG_NAME P12V_OCP_UV_2_R
J 0
(-1410 6410);
DISPLAY 0.574468 (-1410 6410);
FORCEPROP 2 LASTPROP $XRERR UNIQUE?
J 0
(-1650 6410);
DISPLAY 0.638298 (-1650 6410);
PAINT MONO (-1650 6410);
DISPLAY INVISIBLE (-1650 6410);
WIRE 16 -1 (525 6825)(525 6400);
WIRE 16 -1 (525 6825)(175 6825);
WIRE 16 -1 (525 6400)(1050 6400);
FORCEPROP 2 LAST SIG_NAME P12V_OCP_VCC_2
J 0
(590 6410);
DISPLAY 0.574468 (590 6410);
FORCEPROP 2 LASTPROP $XRERR UNIQUE?
J 0
(350 6410);
DISPLAY 0.638298 (350 6410);
PAINT MONO (350 6410);
DISPLAY INVISIBLE (350 6410);
WIRE 16 -1 (175 6925)(175 6825);
WIRE 16 -1 (175 6825)(175 6700);
WIRE 16 -1 (-650 6400)(-150 6400);
WIRE 16 -1 (-150 6625)(-150 6400);
WIRE 16 -1 (-150 6200)(-150 6400);
WIRE 16 -1 (-150 6200)(1050 6200);
FORCEPROP 2 LAST SIG_NAME P12V_OCP_UV_2
J 0
(615 6210);
DISPLAY 0.574468 (615 6210);
FORCEPROP 2 LASTPROP $XRERR UNIQUE?
J 0
(375 6210);
DISPLAY 0.638298 (375 6210);
PAINT MONO (375 6210);
DISPLAY INVISIBLE (375 6210);
WIRE 16 -1 (-150 6200)(-150 6150);
WIRE 16 -1 (-150 5900)(150 5900);
WIRE 16 -1 (-150 5950)(-150 5900);
WIRE 16 -1 (-150 5900)(-150 5875);
WIRE 16 -1 (150 5900)(150 6100);
WIRE 16 -1 (150 6100)(1050 6100);
FORCEPROP 2 LAST SIG_NAME P12V_OCP_OV_2
J 0
(615 6110);
DISPLAY 0.574468 (615 6110);
FORCEPROP 2 LASTPROP $XRERR UNIQUE?
J 0
(375 6110);
DISPLAY 0.638298 (375 6110);
PAINT MONO (375 6110);
DISPLAY INVISIBLE (375 6110);
WIRE 16 -1 (500 6300)(1050 6300);
FORCEPROP 2 LAST SIG_NAME P12V_OCP_REG_2
J 0
(590 6310);
DISPLAY 0.574468 (590 6310);
FORCEPROP 2 LASTPROP $XRERR UNIQUE?
J 0
(350 6310);
DISPLAY 0.638298 (350 6310);
PAINT MONO (350 6310);
DISPLAY INVISIBLE (350 6310);
WIRE 16 2175 (2675 6150)(3400 6150);
WIRE 16 2175 (2675 6150)(2675 5850);
WIRE 16 2175 (3400 6150)(3400 5850);
WIRE 16 2175 (2675 5850)(3400 5850);
WIRE 16 -1 (3175 6100)(4275 6100);
FORCEPROP 2 LAST SIG_NAME P12V_OCP_V3_2_ISENSE_MAM_MAM
J 0
(3415 6110);
DISPLAY 0.574468 (3415 6110);
WIRE 16 -1 (1050 6000)(700 6000);
FORCEPROP 2 LAST SIG_NAME P12V_OCP_CB_2
J 0
(615 6010);
DISPLAY 0.574468 (615 6010);
FORCEPROP 2 LASTPROP $XRERR UNIQUE?
J 0
(375 6010);
DISPLAY 0.638298 (375 6010);
PAINT MONO (375 6010);
DISPLAY INVISIBLE (375 6010);
WIRE 16 -1 (700 6000)(700 5900);
WIRE 16 -1 (3275 6200)(3275 6450);
WIRE 16 -1 (1850 6200)(3275 6200);
FORCEPROP 2 LAST SIG_NAME P12V_OCP_FAULT_2
J 0
(1915 6210);
DISPLAY 0.574468 (1915 6210);
FORCEPROP 2 LASTPROP $XRERR UNIQUE?
J 0
(1675 6210);
DISPLAY 0.638298 (1675 6210);
PAINT MONO (1675 6210);
DISPLAY INVISIBLE (1675 6210);
WIRE 16 -1 (1850 6300)(2825 6300);
FORCEPROP 2 LAST SIG_NAME P12V_OCP_PWRGD_2
J 0
(1915 6310);
DISPLAY 0.574468 (1915 6310);
FORCEPROP 2 LASTPROP $XRERR UNIQUE?
J 0
(1675 6310);
DISPLAY 0.638298 (1675 6310);
PAINT MONO (1675 6310);
DISPLAY INVISIBLE (1675 6310);
WIRE 16 -1 (2625 5975)(2975 5975);
WIRE 16 -1 (2625 6100)(2625 5975);
WIRE 16 -1 (2625 6100)(2975 6100);
WIRE 16 -1 (2300 6100)(2625 6100);
WIRE 16 -1 (2300 6025)(2300 6100);
FORCEPROP 2 LAST SIG_NAME P12V_OCP_SENSE_2
J 0
(1915 6110);
DISPLAY 0.574468 (1915 6110);
FORCEPROP 2 LASTPROP $XRERR UNIQUE?
J 0
(1675 6110);
DISPLAY 0.638298 (1675 6110);
PAINT MONO (1675 6110);
DISPLAY INVISIBLE (1675 6110);
WIRE 16 -1 (1850 6100)(2300 6100);
WIRE 16 -1 (2750 6400)(2575 6400);
WIRE 16 -1 (2575 6525)(2575 6400);
WIRE 16 -1 (2575 6400)(2275 6400);
WIRE 16 -1 (2275 6525)(2275 6400);
WIRE 16 -1 (2275 6400)(1850 6400);
FORCEPROP 2 LAST SIG_NAME P12V_OCP_GATE_2
J 0
(1915 6410);
DISPLAY 0.574468 (1915 6410);
FORCEPROP 2 LASTPROP $XRERR UNIQUE?
J 0
(1675 6410);
DISPLAY 0.638298 (1675 6410);
PAINT MONO (1675 6410);
DISPLAY INVISIBLE (1675 6410);
WIRE 16 -1 (3175 5975)(4275 5975);
FORCEPROP 2 LAST SIG_NAME P12V_OCP_V3_2_ISENSE_MAM_TIC
J 0
(3415 5985);
DISPLAY 0.574468 (3415 5985);
WIRE 16 -1 (-425 8725)(-25 8725);
WIRE 16 -1 (-25 9000)(-25 8725);
WIRE 16 -1 (-25 8525)(-25 8725);
WIRE 16 -1 (-25 8525)(1175 8525);
FORCEPROP 2 LAST SIG_NAME P3V3_OCP_UV_2
J 0
(740 8535);
DISPLAY 0.574468 (740 8535);
FORCEPROP 2 LASTPROP $XRERR UNIQUE?
J 0
(500 8535);
DISPLAY 0.638298 (500 8535);
PAINT MONO (500 8535);
DISPLAY INVISIBLE (500 8535);
WIRE 16 -1 (-25 8525)(-25 8475);
WIRE 16 -1 (-25 8225)(275 8225);
WIRE 16 -1 (-25 8225)(-25 8200);
WIRE 16 -1 (-25 8275)(-25 8225);
WIRE 16 -1 (275 8225)(275 8425);
WIRE 16 -1 (275 8425)(1175 8425);
FORCEPROP 2 LAST SIG_NAME P3V3_OCP_OV_2
J 0
(740 8435);
DISPLAY 0.574468 (740 8435);
FORCEPROP 2 LASTPROP $XRERR UNIQUE?
J 0
(500 8435);
DISPLAY 0.638298 (500 8435);
PAINT MONO (500 8435);
DISPLAY INVISIBLE (500 8435);
WIRE 16 -1 (1175 8325)(825 8325);
FORCEPROP 2 LAST SIG_NAME P3V3_OCP_CB_2
J 0
(740 8335);
DISPLAY 0.574468 (740 8335);
FORCEPROP 2 LASTPROP $XRERR UNIQUE?
J 0
(500 8335);
DISPLAY 0.638298 (500 8335);
PAINT MONO (500 8335);
DISPLAY INVISIBLE (500 8335);
WIRE 16 -1 (825 8325)(825 8225);
WIRE 16 -1 (-2225 8075)(-2225 8200);
WIRE 16 -1 (-2225 8200)(-1775 8200);
FORCEPROP 2 LAST SIG_NAME P3V3_OCP_2_EN_G
J 0
(-2185 8210);
DISPLAY 0.595745 (-2185 8210);
FORCEPROP 2 LASTPROP $XRERR UNIQUE?
J 0
(-2425 8210);
DISPLAY 0.638298 (-2425 8210);
PAINT MONO (-2425 8210);
DISPLAY INVISIBLE (-2425 8210);
WIRE 16 -1 (-2225 8375)(-2225 8200);
WIRE 16 -1 (-1525 8450)(-1525 8725);
WIRE 16 -1 (-625 8725)(-1525 8725);
FORCEPROP 2 LAST SIG_NAME P3V3_OCP_UV_2_R1
J 0
(-1410 8735);
DISPLAY 0.574468 (-1410 8735);
FORCEPROP 2 LASTPROP $XRERR UNIQUE?
J 0
(-1650 8735);
DISPLAY 0.638298 (-1650 8735);
PAINT MONO (-1650 8735);
DISPLAY INVISIBLE (-1650 8735);
WIRE 16 -1 (2675 8875)(2675 8725);
WIRE 16 -1 (2900 8725)(2675 8725);
WIRE 16 -1 (2400 8725)(2675 8725);
WIRE 16 -1 (2400 8850)(2400 8725);
WIRE 16 -1 (2400 8725)(1975 8725);
FORCEPROP 2 LAST SIG_NAME P3V3_OCP_GATE_2
J 0
(2040 8735);
DISPLAY 0.574468 (2040 8735);
FORCEPROP 2 LASTPROP $XRERR UNIQUE?
J 0
(1800 8735);
DISPLAY 0.638298 (1800 8735);
PAINT MONO (1800 8735);
DISPLAY INVISIBLE (1800 8735);
WIRE 16 -1 (300 9250)(300 9150);
WIRE 16 -1 (650 9150)(300 9150);
WIRE 16 -1 (300 9150)(300 9025);
WIRE 16 -1 (650 9150)(650 8725);
WIRE 16 -1 (650 8725)(1175 8725);
FORCEPROP 2 LAST SIG_NAME P3V3_OCP_VCC_2
J 0
(715 8735);
DISPLAY 0.574468 (715 8735);
FORCEPROP 2 LASTPROP $XRERR UNIQUE?
J 0
(475 8735);
DISPLAY 0.638298 (475 8735);
PAINT MONO (475 8735);
DISPLAY INVISIBLE (475 8735);
WIRE 16 -1 (625 8625)(1175 8625);
FORCEPROP 2 LAST SIG_NAME P3V3_OCP_REG_2
J 0
(715 8635);
DISPLAY 0.574468 (715 8635);
FORCEPROP 2 LASTPROP $XRERR UNIQUE?
J 0
(475 8635);
DISPLAY 0.638298 (475 8635);
PAINT MONO (475 8635);
DISPLAY INVISIBLE (475 8635);
WIRE 16 -1 (3425 8525)(3425 8825);
WIRE 16 -1 (1975 8525)(3425 8525);
FORCEPROP 2 LAST SIG_NAME P3V3_OCP_FAULT_2
J 0
(2040 8535);
DISPLAY 0.574468 (2040 8535);
FORCEPROP 2 LASTPROP $XRERR UNIQUE?
J 0
(1800 8535);
DISPLAY 0.638298 (1800 8535);
PAINT MONO (1800 8535);
DISPLAY INVISIBLE (1800 8535);
WIRE 16 -1 (1975 8625)(2975 8625);
FORCEPROP 2 LAST SIG_NAME P3V3_OCP_PWRGD_2
J 0
(2040 8635);
DISPLAY 0.574468 (2040 8635);
FORCEPROP 2 LASTPROP $XRERR UNIQUE?
J 0
(1800 8635);
DISPLAY 0.638298 (1800 8635);
PAINT MONO (1800 8635);
DISPLAY INVISIBLE (1800 8635);
WIRE 16 -1 (4100 8825)(4100 8625);
WIRE 16 -1 (4100 8625)(4175 8625);
WIRE 16 -1 (3175 8625)(4100 8625);
FORCEPROP 2 LAST SIG_NAME OCP_V3_2_P3V3_PWRGD
J 0
(3540 8635);
DISPLAY 0.574468 (3540 8635);
WIRE 16 -1 (1975 8425)(2425 8425);
WIRE 16 -1 (2425 8375)(2425 8425);
FORCEPROP 2 LAST SIG_NAME P3V3_OCP_SENSE_2
J 0
(2040 8435);
DISPLAY 0.574468 (2040 8435);
FORCEPROP 2 LASTPROP $XRERR UNIQUE?
J 0
(1800 8435);
DISPLAY 0.638298 (1800 8435);
PAINT MONO (1800 8435);
DISPLAY INVISIBLE (1800 8435);
WIRE 16 -1 (1925 4850)(1925 4525);
WIRE 16 -1 (1925 4525)(2000 4525);
WIRE 16 -1 (525 4525)(1925 4525);
FORCEPROP 0 LAST CDS_PHYS_NET_NAME HP_LVC3_OCP_V3_2_PRSNT2_N
J 0
(1890 4567);
PAINT MONO (1890 4567);
DISPLAY INVISIBLE (1890 4567);
FORCEPROP 2 LAST SIG_NAME HP_LVC3_OCP_V3_2_PRSNT2_PLD_N
J 0
(825 4535);
DISPLAY 0.553191 (825 4535);
PAINT WHITE (825 4535);
WIRE 16 -1 (-700 4225)(-700 4125);
WIRE 16 -1 (-700 4225)(-700 4525);
WIRE 16 -1 (-700 4225)(-825 4225);
WIRE 16 -1 (-700 4125)(-825 4125);
WIRE 16 -1 (125 4525)(-700 4525);
FORCEPROP 2 LAST SIG_NAME HP_LVC3_OCP_V3_2_PRSNT2_N_R
J 0
(-635 4535);
DISPLAY 0.553191 (-635 4535);
PAINT WHITE (-635 4535);
FORCEPROP 2 LASTPROP $XRERR UNIQUE?
J 0
(-875 4535);
DISPLAY 0.638298 (-875 4535);
PAINT MONO (-875 4535);
DISPLAY INVISIBLE (-875 4535);
WIRE 16 -1 (-700 5025)(-700 4525);
WIRE 16 -1 (-700 5125)(-700 5025);
WIRE 16 -1 (-700 5025)(-825 5025);
WIRE 16 -1 (325 4525)(125 4525);
FORCEPROP 0 LAST CDS_PHYS_NET_NAME HP_LVC3_OCP_V3_2_PRSNT2_N_R
J 0
(215 4567);
PAINT MONO (215 4567);
DISPLAY INVISIBLE (215 4567);
WIRE 16 -1 (125 4525)(125 4275);
WIRE 16 -1 (125 4275)(325 4275);
WIRE 16 -1 (-825 5125)(-700 5125);
WIRE 16 -1 (-1475 4125)(-2300 4125);
FORCEPROP 0 LAST CDS_PHYS_NET_NAME OCP_V3_2_PRSNT3_R_N
J 0
(-1585 4167);
PAINT MONO (-1585 4167);
DISPLAY INVISIBLE (-1585 4167);
FORCEPROP 2 LAST SIG_NAME OCP_V3_2_PRSNT3_R_N
J 0
(-2085 4135);
DISPLAY 0.553191 (-2085 4135);
PAINT WHITE (-2085 4135);
WIRE 16 -1 (-2300 4375)(-2300 4125);
WIRE 16 -1 (-2300 4125)(-2650 4125);
WIRE 16 -1 (1750 4850)(1750 4275);
WIRE 16 -1 (1750 4275)(2025 4275);
WIRE 16 -1 (525 4275)(1750 4275);
FORCEPROP 2 LAST SIG_NAME HP_LVC3_OCP_V3_2_PRSNT2_N
J 0
(840 4285);
DISPLAY 0.553191 (840 4285);
PAINT SKYBLUE (840 4285);
DOT 1 (-2525 4700);
DOT 1 (-2950 8275);
DOT 1 (-2950 7825);
DOT 1 (-2750 6150);
DOT 1 (2157 6750);
DOT 1 (-150 6400);
DOT 1 (950 6750);
DOT 1 (2157 6700);
DOT 1 (-150 6200);
DOT 1 (950 6700);
DOT 1 (175 6825);
DOT 1 (-150 7250);
DOT 1 (2025 5750);
DOT 1 (-2225 8200);
DOT 1 (-25 8725);
DOT 1 (2675 8725);
DOT 1 (-25 8525);
DOT 1 (-25 8225);
DOT 1 (4100 8625);
DOT 1 (2282 9075);
DOT 1 (2075 5750);
DOT 1 (-3100 5825);
DOT 1 (-3075 5825);
DOT 1 (-2350 5125);
DOT 1 (-2075 5025);
DOT 1 (-2300 5600);
DOT 1 (2157 6550);
DOT 1 (1925 5125);
DOT 1 (125 4525);
DOT 1 (1925 4525);
DOT 1 (3875 9750);
DOT 1 (3875 9375);
DOT 1 (3625 9150);
DOT 1 (3300 9750);
DOT 1 (3300 9375);
DOT 1 (2282 9125);
DOT 1 (2282 9025);
DOT 1 (3975 7425);
DOT 1 (3975 7050);
DOT 1 (3575 7425);
DOT 1 (3150 7425);
DOT 1 (3575 7050);
DOT 1 (3150 7050);
DOT 1 (2400 8725);
DOT 1 (2675 7425);
DOT 1 (1075 9125);
DOT 1 (1075 9025);
DOT 1 (1075 8925);
DOT 1 (950 6800);
DOT 1 (175 7250);
DOT 1 (2157 6600);
DOT 1 (2275 6400);
DOT 1 (2175 5750);
DOT 1 (1975 5750);
DOT 1 (950 6550);
DOT 1 (700 5600);
DOT 1 (-375 9575);
DOT 1 (-500 7250);
DOT 1 (-725 7250);
DOT 1 (-150 5900);
DOT 1 (-475 5075);
DOT 1 (-700 5025);
DOT 1 (-475 4175);
DOT 1 (-700 4525);
DOT 1 (-700 4225);
DOT 1 (-2525 4225);
DOT 1 (-2300 4125);
DOT 1 (-2725 7825);
DOT 1 (-725 6760);
DOT 1 (2200 8075);
DOT 1 (825 7925);
DOT 1 (1750 4275);
DOT 1 (2100 8075);
DOT 1 (2150 8075);
DOT 1 (2800 9750);
DOT 1 (2282 8925);
DOT 1 (2400 9125);
DOT 1 (2282 8875);
DOT 1 (2495 9125);
DOT 1 (2300 8075);
DOT 1 (2282 8975);
DOT 1 (-25 9575);
DOT 1 (300 9150);
DOT 1 (1075 9075);
DOT 1 (300 9575);
DOT 1 (300 8625);
DOT 1 (1075 8975);
DOT 1 (1075 8875);
DOT 1 (2275 6800);
DOT 1 (2157 6650);
DOT 1 (2370 6800);
DOT 1 (3700 6300);
DOT 1 (2300 6100);
DOT 1 (2575 6400);
DOT 1 (3475 6800);
DOT 1 (2625 6100);
DOT 1 (2157 6800);
DOT 1 (950 6600);
DOT 1 (950 6650);
DOT 1 (175 6300);
FORCENOTE
VIMON(MAX)= 1.594V @ IOUT=1.6A
(1025 7725) 0;
DISPLAY LEFT (1025 7725);
DISPLAY 1.021277 (1025 7725);
PAINT WHITE (1025 7725);
FORCENOTE
UVP: 2.63V
(-550 8425) 0;
DISPLAY LEFT (-550 8425);
DISPLAY 1.021277 (-550 8425);
PAINT WHITE (-550 8425);
FORCENOTE
OVP: 3.89V
(-550 8350) 0;
DISPLAY LEFT (-550 8350);
DISPLAY 1.021277 (-550 8350);
PAINT WHITE (-550 8350);
FORCENOTE
IMAX=1.1A
(-4200 9600) 0;
DISPLAY LEFT (-4200 9600);
DISPLAY 0.936170 (-4200 9600);
FORCENOTE
DESIGN SPECIFICATION
(-4243 9777) 0;
DISPLAY LEFT (-4243 9777);
DISPLAY 1.170213 (-4243 9777);
FORCENOTE
P3V3_OCP_V3_2_R
(-4200 9675) 0;
DISPLAY LEFT (-4200 9675);
DISPLAY 0.936170 (-4200 9675);
FORCENOTE
P12V_OCP_V3_2
(-4200 9275) 0;
DISPLAY LEFT (-4200 9275);
DISPLAY 1.021277 (-4200 9275);
FORCENOTE
OCP=IMAX*1.3=1.43A
(-4200 9525) 0;
DISPLAY LEFT (-4200 9525);
DISPLAY 0.936170 (-4200 9525);
FORCENOTE
IMAX=6.6A
(-4200 9200) 0;
DISPLAY LEFT (-4200 9200);
DISPLAY 1.021277 (-4200 9200);
FORCENOTE
VIMON(MAX)= 1.679V @ IOUT=9.03A
(1025 5400) 0;
DISPLAY LEFT (1025 5400);
DISPLAY 1.021277 (1025 5400);
PAINT WHITE (1025 5400);
FORCENOTE
FROM CPLD
(-4375 5900) 0;
DISPLAY LEFT (-4375 5900);
DISPLAY 1.021277 (-4375 5900);
FORCENOTE
START UP TIME:3.94MS
(2875 8325) 0;
DISPLAY LEFT (2875 8325);
DISPLAY 1.021277 (2875 8325);
PAINT WHITE (2875 8325);
FORCENOTE
START UP TIME:8.21MS
(3350 6175) 0;
DISPLAY LEFT (3350 6175);
DISPLAY 1.021277 (3350 6175);
PAINT WHITE (3350 6175);
FORCENOTE
OVP: 14.91V
(-725 6075) 0;
DISPLAY LEFT (-725 6075);
DISPLAY 1.021277 (-725 6075);
PAINT WHITE (-725 6075);
FORCENOTE
UVP: 10.17V
(-725 6150) 0;
DISPLAY LEFT (-725 6150);
DISPLAY 1.021277 (-725 6150);
PAINT WHITE (-725 6150);
FORCENOTE
FROM PRSNT BUFFER
(-4375 6225) 0;
DISPLAY LEFT (-4375 6225);
DISPLAY 1.021277 (-4375 6225);
FORCENOTE
FROM PRSNT BUFFER
(-4500 8650) 0;
DISPLAY LEFT (-4500 8650);
DISPLAY 1.021277 (-4500 8650);
FORCENOTE
OCP=IMAX*1.3=8.58A
(-4200 9125) 0;
DISPLAY LEFT (-4200 9125);
DISPLAY 1.021277 (-4200 9125);
QUIT
